G04 ================== begin FILE IDENTIFICATION RECORD ==================*
G04 Layout Name:  12523-1.brd*
G04 Film Name:    TSILK*
G04 File Format:  Gerber RS274X*
G04 File Origin:  Cadence Allegro 16.2-s031*
G04 Origin Date:  Fri Oct 19 14:59:09 2012*
G04 *
G04 Layer:  VIA CLASS/FILMMASKTOP*
G04 Layer:  REF DES/ASSEMBLY_TOP*
G04 Layer:  PACKAGE GEOMETRY/SILKSCREEN_TOP*
G04 Layer:  DRAWING FORMAT/LAYER_PCB_STORY*
G04 Layer:  DRAWING FORMAT/LAYER_SILK_T*
G04 Layer:  BOARD GEOMETRY/SILKSCREEN_TOP*
G04 *
G04 Offset:    (0.00 0.00)*
G04 Mirror:    No*
G04 Mode:      Positive*
G04 Rotation:  0*
G04 FullContactRelief:  No*
G04 UndefLineWidth:     6.00*
G04 ================== end FILE IDENTIFICATION RECORD ====================*
%FSLAX35Y35*MOIN*%
%IR0*IPPOS*OFA0.00000B0.00000*MIA0B0*SFA1.00000B1.00000*%
%ADD10C,.01*%
%ADD11C,.02*%
%ADD12C,.012*%
%ADD13C,.013*%
%ADD14C,.025*%
%ADD15C,.002*%
%ADD16C,.006*%
%ADD17C,.008*%
G75*
%LPD*%
G75*
G36*
G01X49042Y375502D02*
X58042D01*
Y367502D01*
X49042D01*
Y375502D01*
G37*
G36*
G01X277500Y83000D02*
Y78000D01*
X297500D01*
Y83000D01*
X277500D01*
G37*
G36*
G01X626235Y384776D02*
X623535D01*
Y382176D01*
X626235D01*
Y384776D01*
G37*
G36*
G01X353500Y215900D02*
X317100D01*
Y453100D01*
X353500D01*
Y215900D01*
G37*
G54D10*
G01X126489Y-19685D02*
G03X116016I-5236J0D01*
G01X157984D02*
G03X147511I-5236J0D01*
G01X220974D02*
G03X210502I-5236J0D01*
G01X189479D02*
G03X179007I-5236J0D01*
G01X283964D02*
G03X273492I-5236J0D01*
G01X252469D02*
G03X241997I-5236J0D01*
G54D11*
G01X-4246Y-109426D02*
Y-189426D01*
G01D02*
X1290354D01*
G01X-4246Y-144926D02*
X1290354D01*
G01X-8246Y-93426D02*
G02I-12000J0D01*
G01X-13396D02*
G02I-6850J0D01*
G01X-20246Y-109426D02*
Y-77426D01*
G01X-4246Y-93426D02*
X-36246D01*
G01X-4246Y-109426D02*
X1290354D01*
G01X6797Y193619D02*
X11797D01*
G01X-2303D02*
X2697D01*
G01X125000Y209500D02*
X406500D01*
Y143500D01*
X111000D01*
Y209500D01*
X125000D01*
G01X502854Y-109426D02*
Y-189426D01*
G01X504689Y167262D02*
X521289D01*
G01X479325Y167186D02*
X495925D01*
G01X470398Y186436D02*
X475398D01*
G01X529835Y167277D02*
X546435D01*
G01X636838Y80903D02*
X632188D01*
G01X623985Y336676D02*
Y353376D01*
G01X640354Y-109426D02*
Y-189426D01*
G01X755354Y-109426D02*
Y-189426D01*
G01X922854Y-109426D02*
Y-189426D01*
G01X1092854Y-109426D02*
Y-189426D01*
G01X1290354Y-109426D02*
Y-189426D01*
G01X1318354Y-93426D02*
G02I-12000J0D01*
G01X1313204D02*
G02I-6850J0D01*
G01X1306354Y-109426D02*
Y-77426D01*
G01X1322354Y-93426D02*
X1290354D01*
G54D12*
G01X0Y50259D02*
Y75460D01*
G01Y426594D02*
Y401397D01*
G01Y555771D02*
Y530574D01*
G01Y906909D02*
Y881711D01*
G01X77283Y0D02*
X107993D01*
G01X77283Y472441D02*
X107993D01*
G01X77283Y480315D02*
X107993D01*
G01X77283Y952756D02*
X107993D01*
G01X335552Y0D02*
X304843D01*
G01Y472441D02*
X335552D01*
G01X304843Y480315D02*
X335552D01*
G01X304843Y952756D02*
X335552D01*
G01X532402Y0D02*
X563111D01*
G01X574959Y161889D02*
G02I-4250J0D01*
G01X584959D02*
G02I-4250J0D01*
G01X574959Y214409D02*
G02I-4250J0D01*
G01Y204409D02*
G02I-4250J0D01*
G01Y191889D02*
G02I-4250J0D01*
G01Y181889D02*
G02I-4250J0D01*
G01Y171889D02*
G02I-4250J0D01*
G01X584959Y214409D02*
G02I-4250J0D01*
G01Y204409D02*
G02I-4250J0D01*
G01Y191889D02*
G02I-4250J0D01*
G01Y181889D02*
G02I-4250J0D01*
G01Y171889D02*
G02I-4250J0D01*
G01X574959Y244409D02*
G02I-4250J0D01*
G01X584959D02*
G02I-4250J0D01*
G01X574959Y276929D02*
G02I-4250J0D01*
G01Y266929D02*
G02I-4250J0D01*
G01Y256929D02*
G02I-4250J0D01*
G01Y234409D02*
G02I-4250J0D01*
G01Y224409D02*
G02I-4250J0D01*
G01X584959Y276929D02*
G02I-4250J0D01*
G01Y266929D02*
G02I-4250J0D01*
G01Y256929D02*
G02I-4250J0D01*
G01Y234409D02*
G02I-4250J0D01*
G01Y224409D02*
G02I-4250J0D01*
G01X574959Y286929D02*
G02I-4250J0D01*
G01X584959D02*
G02I-4250J0D01*
G01X532402Y472441D02*
X563111D01*
G01X532402Y480315D02*
X563111D01*
G01X532402Y952756D02*
X563111D01*
G01X597958Y74803D02*
G02I4050J0D01*
G01X592052Y66929D02*
G02I4050J0D01*
G01Y82677D02*
G02I4050J0D01*
G01X594959Y161889D02*
G02I-4250J0D01*
G01X604959D02*
G02I-4250J0D01*
G01X594959Y214409D02*
G02I-4250J0D01*
G01Y204409D02*
G02I-4250J0D01*
G01Y191889D02*
G02I-4250J0D01*
G01Y181889D02*
G02I-4250J0D01*
G01Y171889D02*
G02I-4250J0D01*
G01X604959Y214409D02*
G02I-4250J0D01*
G01Y204409D02*
G02I-4250J0D01*
G01Y191889D02*
G02I-4250J0D01*
G01Y181889D02*
G02I-4250J0D01*
G01Y171889D02*
G02I-4250J0D01*
G01Y244409D02*
G02I-4250J0D01*
G01X594959D02*
G02I-4250J0D01*
G01Y276929D02*
G02I-4250J0D01*
G01Y266929D02*
G02I-4250J0D01*
G01Y256929D02*
G02I-4250J0D01*
G01Y234409D02*
G02I-4250J0D01*
G01Y224409D02*
G02I-4250J0D01*
G01X604959Y276929D02*
G02I-4250J0D01*
G01Y266929D02*
G02I-4250J0D01*
G01Y256929D02*
G02I-4250J0D01*
G01Y234409D02*
G02I-4250J0D01*
G01Y224409D02*
G02I-4250J0D01*
G01X594959Y286929D02*
G02I-4250J0D01*
G01X604959D02*
G02I-4250J0D01*
G01X648267Y34437D02*
Y65146D01*
G01X640393Y34437D02*
Y65146D01*
G01X648267Y438004D02*
Y407295D01*
G01X640393Y438004D02*
Y407295D01*
G01X648267Y545462D02*
Y514753D01*
G01X640393Y545462D02*
Y514753D01*
G01X648267Y918320D02*
Y887611D01*
G01X640393Y918320D02*
Y887611D01*
G01X756261Y0D02*
X725552D01*
G01Y472441D02*
X756261D01*
G01X725552Y480315D02*
X756261D01*
G01X725552Y952756D02*
X756261D01*
G01X983820Y0D02*
X953111D01*
G01Y472441D02*
X983820D01*
G01X953111Y480315D02*
X983820D01*
G01X953111Y952756D02*
X983820D01*
G01X1180670Y0D02*
X1211380D01*
G01X1180670Y472441D02*
X1211380D01*
G01X1180670Y480315D02*
X1211380D01*
G01Y952756D02*
X1180670D01*
G01X1288660Y71044D02*
Y45847D01*
G01Y422182D02*
Y396985D01*
G01Y551359D02*
Y526162D01*
G01Y902497D02*
Y877296D01*
G54D13*
G01X631538Y81303D02*
Y79453D01*
G01X637438Y81303D02*
Y79453D01*
G54D14*
G01X47042Y367402D02*
Y359802D01*
G54D15*
G01X280670Y88090D02*
X280010D01*
G01X280110Y88180D02*
X280770D01*
G01X280860Y88290D02*
X280210D01*
G01X280310Y88380D02*
X280960D01*
G01X281060Y88490D02*
X280400D01*
G01X280500Y88590D02*
X281150D01*
G01X281250Y88680D02*
X280600D01*
G01X280690Y88790D02*
X281350D01*
G01X281440Y88880D02*
X280790D01*
G01X280880Y88990D02*
X281540D01*
G01X281640Y89090D02*
X280980D01*
G01X281080Y89180D02*
X281730D01*
G01X281830Y89290D02*
X281185D01*
G01X281180D02*
X281230D01*
G01X281270Y89380D02*
X281310D01*
G01X281270D02*
X281920D01*
G01X282020Y89490D02*
X281370D01*
G01X281470Y89590D02*
X282120D01*
G01X282220Y89680D02*
X281560D01*
G01X281660Y89790D02*
X282310D01*
G01X282410Y89880D02*
X281750D01*
G01X281850Y89990D02*
X282510D01*
G01X282600Y90090D02*
X281950D01*
G01X282050Y90180D02*
X282700D01*
G01X282790Y90290D02*
X282140D01*
G01X282240Y90380D02*
X282890D01*
G01X282990Y90490D02*
X282330D01*
G01X282430Y90590D02*
X283090D01*
G01X283180Y90680D02*
X282530D01*
G01X282620Y90790D02*
X283280D01*
G01X283470Y90990D02*
X282820D01*
G01X283010Y91180D02*
X283660D01*
G01X283620Y99330D02*
X278440Y104920D01*
G01X280140Y103090D02*
X280750D01*
G01X280850Y102990D02*
X280230D01*
G01X280330Y102880D02*
X280940D01*
G01X281030Y102790D02*
X280420D01*
G01X280510Y102680D02*
X281120D01*
G01X281220Y102590D02*
X280610D01*
G01X280700Y102490D02*
X281310D01*
G01X281400Y102380D02*
X280790D01*
G01X280880Y102290D02*
X281500D01*
G01X281590Y102180D02*
X280980D01*
G01X281070Y102090D02*
X281680D01*
G01X281780Y101990D02*
X281160D01*
G01X281250Y101880D02*
X281870D01*
G01X281960Y101790D02*
X281350D01*
G01X281440Y101680D02*
X282060D01*
G01X282150Y101590D02*
X281530D01*
G01X281620Y101490D02*
X282240D01*
G01X282340Y101380D02*
X281720D01*
G01X281810Y101290D02*
X282430D01*
G01X282520Y101180D02*
X281900D01*
G01X281990Y101090D02*
X282620D01*
G01X282710Y100990D02*
X282090D01*
G01X282180Y100880D02*
X282800D01*
G01X282890Y100790D02*
X282270D01*
G01X282370Y100680D02*
X282990D01*
G01X283080Y100590D02*
X282460D01*
G01X282550Y100490D02*
X283170D01*
G01X283270Y100380D02*
X282650D01*
G01X282830Y100180D02*
X284070D01*
G01X284080Y99990D02*
X283020D01*
G01X282770Y102280D02*
X283280D01*
G01X282730Y102240D02*
X282770Y102280D01*
G01X282730Y101780D02*
Y102240D01*
G01X282770Y101740D02*
X282730Y101780D01*
G01Y102180D02*
X292980D01*
G01X292910Y101990D02*
X282730D01*
G01Y101790D02*
X292750D01*
G01X285380Y103090D02*
X283950D01*
G01X283370Y102350D02*
X283280Y102280D01*
G01X283390Y102400D02*
X283370Y102350D01*
G01X283390Y102410D02*
Y102400D01*
G01X283510Y102660D02*
X283390Y102410D01*
G01X283530Y102670D02*
X283510Y102660D01*
G01X283960Y103090D02*
X283530Y102670D01*
G01X283290Y102290D02*
X284020D01*
G01X284130Y102620D02*
X284240Y102690D01*
G01X283960Y102450D02*
X284130Y102620D01*
G01X283940Y102340D02*
X283960Y102450D01*
G01X284030Y102280D02*
X283940Y102340D01*
G01X284100Y102590D02*
X283480D01*
G01X283430Y102490D02*
X284000D01*
G01X283950Y102380D02*
X283380D01*
G01X283640Y102790D02*
X285320D01*
G01Y102990D02*
X283850D01*
G01X284200Y99390D02*
X287430Y95910D01*
G01X284190Y99390D02*
X284200D01*
G01X284150Y99440D02*
X284190Y99390D01*
G01X284120Y99500D02*
X284150Y99440D01*
G01X283940Y101630D02*
X284120Y99500D01*
G01X284040Y101740D02*
X283940Y101630D01*
G01X284460Y95590D02*
X283990D01*
G01X283980Y95790D02*
X284440D01*
G01X284420Y95990D02*
X283960D01*
G01X283940Y96180D02*
X284410D01*
G01X284390Y96380D02*
X283920D01*
G01X283900Y96590D02*
X284370D01*
G01X284360Y96790D02*
X283890D01*
G01X283870Y96990D02*
X284340D01*
G01X284320Y97180D02*
X283850D01*
G01X283840Y97380D02*
X284310D01*
G01X284290Y97590D02*
X283820D01*
G01X283800Y97790D02*
X284270D01*
G01X284250Y97990D02*
X283790D01*
G01X283770Y98180D02*
X284240D01*
G01X284220Y98380D02*
X283750D01*
G01X283740Y98490D02*
X284250D01*
G01X284750Y98790D02*
X283720D01*
G01X283700Y98990D02*
X284570D01*
G01X283640Y99300D02*
X283620Y99330D01*
G01X283680Y99200D02*
X283640Y99300D01*
G01X283680Y99190D02*
Y99200D01*
G01Y99180D02*
Y99190D01*
G01X284380Y99180D02*
X283680D01*
G01X283580Y99380D02*
X284200D01*
G01X284130Y99490D02*
X283480D01*
G01X283390Y99590D02*
X284120D01*
G01X284110Y99680D02*
X283300D01*
G01X283200Y99790D02*
X284100D01*
G01X284090Y99880D02*
X283110D01*
G01X282920Y100090D02*
X284070D01*
G01X284060Y100290D02*
X283580D01*
G01X283370Y101740D02*
X282770D01*
G01X283470Y101650D02*
X283370Y101740D01*
G01X283590Y100300D02*
X283470Y101650D01*
G01X283430Y101680D02*
X283990D01*
G01X283940Y101590D02*
X283480D01*
G01X283490Y101490D02*
X283960D01*
G01Y101380D02*
X283490D01*
G01X283500Y101290D02*
X283970D01*
G01X283980Y101180D02*
X283510D01*
G01X283520Y101090D02*
X283990D01*
G01X284000Y100990D02*
X283530D01*
G01X283540Y100880D02*
X284010D01*
G01Y100790D02*
X283550D01*
G01Y100680D02*
X284020D01*
G01X284030Y100590D02*
X283570D01*
G01Y100490D02*
X284040D01*
G01X284050Y100380D02*
X283580D01*
G01X283420Y100230D02*
X278400Y105620D01*
G01X283530Y100200D02*
X283420Y100230D01*
G01X283590Y100300D02*
X283530Y100200D01*
G01X282740Y100290D02*
X283360D01*
G01X283680Y99180D02*
X284120Y94030D01*
G01X284130Y93990D02*
X284600D01*
G01X284610Y93790D02*
X284140D01*
G01X284160Y93590D02*
X284630D01*
G01X284650Y93380D02*
X284180D01*
G01X284200Y93180D02*
X284670D01*
G01X284710Y93090D02*
X284210D01*
G01X284220Y92440D02*
X284120Y92330D01*
G01X284250Y92510D02*
X284220Y92440D01*
G01X284070Y92290D02*
X284760D01*
G01Y92090D02*
X283880D01*
G01X283690Y91880D02*
X284780D01*
G01X284140Y91680D02*
X283490D01*
G01X283400Y91590D02*
X284050D01*
G01X283950Y91490D02*
X283300D01*
G01X283200Y91380D02*
X283860D01*
G01X283760Y91290D02*
X283110D01*
G01X282920Y91090D02*
X283570D01*
G01X283370Y90880D02*
X282720D01*
G01X284100Y94290D02*
X284570D01*
G01X284550Y94490D02*
X284090D01*
G01X284070Y94680D02*
X284540D01*
G01X284520Y94880D02*
X284050D01*
G01X284030Y95090D02*
X284500D01*
G01X284490Y95290D02*
X284020D01*
G01X284010Y95380D02*
X284480D01*
G01X284470Y95490D02*
X284000D01*
G01X283980Y95680D02*
X284450D01*
G01X284440Y95880D02*
X283970D01*
G01X283950Y96090D02*
X284420D01*
G01X284400Y96290D02*
X283930D01*
G01X283920Y96490D02*
X284380D01*
G01X284360Y96680D02*
X283900D01*
G01X283880Y96880D02*
X284350D01*
G01X284330Y97090D02*
X283860D01*
G01X283850Y97290D02*
X284310D01*
G01X284300Y97490D02*
X283830D01*
G01X283810Y97680D02*
X284280D01*
G01X284260Y97880D02*
X283790D01*
G01X283780Y98090D02*
X284240D01*
G01X284230Y98290D02*
X283760D01*
G01X284390Y98510D02*
X287120Y95570D01*
G01X284270Y98530D02*
X284390Y98510D01*
G01X284220Y98430D02*
X284270Y98530D01*
G01X284490Y95180D02*
X284030D01*
G01X284040Y94990D02*
X284510D01*
G01X284530Y94790D02*
X284060D01*
G01X284080Y94590D02*
X284550D01*
G01X284560Y94380D02*
X284090D01*
G01X284110Y94180D02*
X284580D01*
G01X284590Y94090D02*
X284120D01*
G01X284250Y92570D02*
Y92510D01*
G01X284120Y94030D02*
X284250Y92570D01*
G01X284240Y92490D02*
X284920D01*
G01X284770Y92310D02*
X284750Y92240D01*
G01X284820Y92390D02*
X284770Y92310D01*
G01X284750Y92180D02*
X283980D01*
G01X283790Y91990D02*
X284770D01*
G01X284790Y91680D02*
X284290D01*
G01X284260Y91720D02*
X284160Y91700D01*
G01X284530Y89280D02*
X284640D01*
G01X284530Y89290D02*
Y89280D01*
G01X284330Y91640D02*
X284530Y89290D01*
G01X284260Y91720D02*
X284330Y91640D01*
G01X284630Y89380D02*
X284520D01*
G01X284525D02*
X290120D01*
G01X290185Y89290D02*
X284530D01*
G01X284770Y88240D02*
X285660D01*
G01X284730Y88280D02*
X284770Y88240D01*
G01X284730Y88960D02*
Y88280D01*
G01X284700Y89030D02*
X284730Y88960D01*
G01X284550Y89190D02*
X284700Y89030D01*
G01X284540Y89210D02*
X284550Y89190D01*
G01X284530Y89270D02*
X284540Y89210D01*
G01X285700Y88290D02*
X284730D01*
G01Y88490D02*
X285700D01*
G01Y88680D02*
X284730D01*
G01Y88880D02*
X285700D01*
G01X284980Y89590D02*
X284510D01*
G01X284490Y89680D02*
X284960D01*
G01X284950Y89880D02*
X284480D01*
G01X284460Y90090D02*
X284930D01*
G01X284910Y90290D02*
X284440D01*
G01X284430Y90490D02*
X284900D01*
G01X284880Y90680D02*
X284410D01*
G01X284390Y90880D02*
X284860D01*
G01X284850Y91090D02*
X284380D01*
G01X284360Y91290D02*
X284830D01*
G01X284810Y91490D02*
X284350D01*
G01X284240Y92680D02*
X285110D01*
G01X285300Y92880D02*
X284220D01*
G01X284190Y93290D02*
X284660D01*
G01X284670Y93140D02*
X284220Y98430D01*
G01X284410Y98490D02*
X285030D01*
G01X285220Y98290D02*
X284600D01*
G01X284780Y98090D02*
X285400D01*
G01X284660Y98880D02*
X283710D01*
G01X283690Y99090D02*
X284480D01*
G01X284290Y99290D02*
X283650D01*
G01X284350Y102700D02*
X284240Y102690D01*
G01X284400Y102610D02*
X284350Y102700D01*
G01X284400Y102380D02*
Y102610D01*
G01X284300Y102280D02*
X284400Y102380D01*
G01X284030Y102280D02*
X284300D01*
G01X284230Y102680D02*
X283540D01*
G01X283960Y103090D02*
X284230Y103250D01*
G01X284350Y102680D02*
X285320D01*
G01Y102490D02*
X284400D01*
G01X284310Y102290D02*
X285420D01*
G01X284610Y93880D02*
X284140D01*
G01X284150Y93680D02*
X284620D01*
G01X284640Y93490D02*
X284170D01*
G01X284740Y93050D02*
X284840Y93080D01*
G01X284670Y93140D02*
X284740Y93050D01*
G01X284650Y89090D02*
X290430D01*
G01X284970Y89660D02*
X284750Y92240D01*
G01X284970Y89590D02*
Y89660D01*
G01X285070Y89500D02*
X284970Y89590D01*
G01X289170Y89500D02*
X285070D01*
G01X284820Y92380D02*
X284170D01*
G01X284250Y92590D02*
X285010D01*
G01X284830Y92390D02*
X284820D01*
G01X284830Y92400D02*
Y92390D01*
G01Y92400D02*
X287420Y95090D01*
G01X287230Y94880D02*
X286590D01*
G01X286390Y94680D02*
X287040D01*
G01X286850Y94490D02*
X286200D01*
G01X286010Y94290D02*
X286650D01*
G01X286560Y94180D02*
X285910D01*
G01X285960Y94240D02*
X284840Y93080D01*
G01X284850Y93090D02*
X285490D01*
G01X285400Y92990D02*
X284220D01*
G01X284230Y92790D02*
X285210D01*
G01X284950Y93180D02*
X285590D01*
G01X285690Y93290D02*
X285050D01*
G01X285140Y93380D02*
X285790D01*
G01X285880Y93490D02*
X285240D01*
G01X285330Y93590D02*
X285980D01*
G01X286070Y93680D02*
X285430D01*
G01X285530Y93790D02*
X286170D01*
G01X286270Y93880D02*
X285620D01*
G01X285720Y93990D02*
X286360D01*
G01X286460Y94090D02*
X285810D01*
G01X286640Y96090D02*
X287270D01*
G01X287080Y96290D02*
X286460D01*
G01X286270Y96490D02*
X286890D01*
G01X286710Y96680D02*
X286080D01*
G01X285990Y96790D02*
X286610D01*
G01X286520Y96880D02*
X285900D01*
G01X285810Y96990D02*
X286430D01*
G01X286330Y97090D02*
X285710D01*
G01X285620Y97180D02*
X286240D01*
G01X286150Y97290D02*
X285530D01*
G01X285430Y97380D02*
X286060D01*
G01X285960Y97490D02*
X285340D01*
G01X285250Y97590D02*
X285870D01*
G01X285780Y97680D02*
X285150D01*
G01X285060Y97790D02*
X285680D01*
G01X285590Y97880D02*
X284970D01*
G01X284880Y97990D02*
X285500D01*
G01X285310Y98180D02*
X284690D01*
G01X284500Y98380D02*
X285120D01*
G01X284940Y98590D02*
X283740D01*
G01X283730Y98680D02*
X284850D01*
G01X286700Y97960D02*
X286740Y97920D01*
G01X285320Y102380D02*
X284400D01*
G01X285420Y102280D02*
X285320Y102380D01*
G01X284400Y102590D02*
X285320D01*
G01X285400Y103120D02*
X285520Y103140D01*
G01X285320Y103020D02*
X285400Y103120D01*
G01X285320Y102380D02*
Y103020D01*
G01Y102880D02*
X283750D01*
G01X285420Y102280D02*
X291260D01*
G01X284790Y91790D02*
X283590D01*
G01X284330Y91590D02*
X284800D01*
G01X284820Y91380D02*
X284350D01*
G01X284370Y91180D02*
X284840D01*
G01X284850Y90990D02*
X284380D01*
G01X284400Y90790D02*
X284870D01*
G01X284890Y90590D02*
X284420D01*
G01X284440Y90380D02*
X284900D01*
G01X284920Y90180D02*
X284460D01*
G01X284470Y89990D02*
X284940D01*
G01X284960Y89790D02*
X284490D01*
G01X284720Y88990D02*
X285770D01*
G01X285700Y88280D02*
X285660Y88240D01*
G01X285700Y88920D02*
Y88280D01*
G01X285800Y89020D02*
X285700Y88920D01*
G01Y88380D02*
X284730D01*
G01Y88590D02*
X285700D01*
G01Y88790D02*
X284730D01*
G01X289270Y89970D02*
Y89980D01*
G01X289260Y89900D02*
X289270Y89970D01*
G01X289260Y89640D02*
Y89900D01*
G01X289270Y89620D02*
X289260Y89640D01*
G01X289170Y89500D02*
X289270Y89620D01*
G01Y89990D02*
X290040D01*
G01X290000Y89790D02*
X289260D01*
G01X289240Y89590D02*
X290040D01*
G01X287880Y95420D02*
Y95560D01*
G01X290580Y92520D02*
X287880Y95420D01*
G01X287900Y95590D02*
X287110D01*
G01X287120Y95430D02*
X285960Y94240D01*
G01X287120Y95570D02*
Y95430D01*
G01X286110Y94380D02*
X286750D01*
G01X286940Y94590D02*
X286300D01*
G01X286490Y94790D02*
X287140D01*
G01X287330Y94990D02*
X286680D01*
G01X287570Y95090D02*
X289250Y93270D01*
G01X287420Y95090D02*
X287570D01*
G01X286780D02*
X287420D01*
G01X289240Y93290D02*
X289870D01*
G01X289680Y93490D02*
X289050D01*
G01X288870Y93680D02*
X289500D01*
G01X289310Y93880D02*
X288680D01*
G01X288590Y93990D02*
X289220D01*
G01X289120Y94090D02*
X288490D01*
G01X288400Y94180D02*
X289030D01*
G01X288940Y94290D02*
X288310D01*
G01X288220Y94380D02*
X288850D01*
G01X288750Y94490D02*
X288120D01*
G01X288030Y94590D02*
X288660D01*
G01X288570Y94680D02*
X287940D01*
G01X287850Y94790D02*
X288480D01*
G01X288380Y94880D02*
X287750D01*
G01X287660Y94990D02*
X288290D01*
G01X288200Y95090D02*
X287550D01*
G01X287920Y95380D02*
X287070D01*
G01X287120Y95490D02*
X287880D01*
G01X288000Y95680D02*
X287010D01*
G01X286920Y95790D02*
X288100D01*
G01X288200Y95880D02*
X286830D01*
G01X286740Y95990D02*
X287360D01*
G01X287570Y95910D02*
X289000Y97380D01*
G01X287430Y95910D02*
X287570D01*
G01X288900Y97290D02*
X289540D01*
G01X289350Y97090D02*
X288710D01*
G01X288620Y96990D02*
X289250D01*
G01X289160Y96880D02*
X288520D01*
G01X288420Y96790D02*
X289060D01*
G01X288970Y96680D02*
X288330D01*
G01X288230Y96590D02*
X288870D01*
G01X288770Y96490D02*
X288130D01*
G01X288040Y96380D02*
X288680D01*
G01X288580Y96290D02*
X287940D01*
G01X287850Y96180D02*
X288480D01*
G01X288390Y96090D02*
X287750D01*
G01X287650Y95990D02*
X288290D01*
G01X288010Y95290D02*
X286980D01*
G01X286880Y95180D02*
X288100D01*
G01X287170Y96180D02*
X286550D01*
G01X286360Y96380D02*
X286990D01*
G01X286800Y96590D02*
X286180D01*
G01X286790Y97920D02*
X289280D01*
G01X286740D02*
X286790D01*
G01X289290Y97680D02*
X289930D01*
G01X289740Y97490D02*
X289100D01*
G01X290220Y97990D02*
X286700D01*
G01X286740Y98950D02*
X286790D01*
G01X286700Y98910D02*
X286740Y98950D01*
G01X286700Y97960D02*
Y98910D01*
G01Y98790D02*
X289960D01*
G01X289990Y98590D02*
X286700D01*
G01Y98380D02*
X290610D01*
G01X290410Y98180D02*
X286700D01*
G01X286760Y102840D02*
Y103180D01*
G01X286800Y102790D02*
X286760Y102840D01*
G01X289250Y102790D02*
X286800D01*
G01X289300Y102840D02*
X289250Y102790D01*
G01X289300Y103120D02*
Y102840D01*
G01X286760Y102880D02*
X289300D01*
G01Y102990D02*
X286760D01*
G01Y103090D02*
X289300D01*
G01X289810Y103150D02*
X290220Y103060D01*
G01X289300Y103120D02*
X289410Y103220D01*
G01X289910Y98950D02*
X286790D01*
G01X286700Y98880D02*
X289960D01*
G01X289950Y98910D02*
X289910Y98950D01*
G01X290130Y98560D02*
X290330Y98760D01*
G01X290020Y98530D02*
X290130Y98560D01*
G01X289960Y98630D02*
X290020Y98530D01*
G01X289960Y98810D02*
Y98630D01*
G01Y98820D02*
Y98810D01*
G01X289950Y98910D02*
X289960Y98820D01*
G01X290160Y98590D02*
X290800D01*
G01X289960Y98680D02*
X286700D01*
G01X288810Y97180D02*
X289450D01*
G01X289370Y97860D02*
X289280Y97920D01*
G01X289350Y97750D02*
X289370Y97860D01*
G01X289000Y97380D02*
X289350Y97750D01*
G01X289640Y97380D02*
X289000D01*
G01X289330Y97880D02*
X290120D01*
G01X290030Y97790D02*
X289360D01*
G01X289200Y97590D02*
X289830D01*
G01X289400Y93790D02*
X288770D01*
G01X288960Y93590D02*
X289590D01*
G01X289770Y93380D02*
X289140D01*
G01X289330Y93180D02*
X289960D01*
G01X290050Y93090D02*
X289420D01*
G01X289510Y92990D02*
X290150D01*
G01X290240Y92880D02*
X289610D01*
G01X289700Y92790D02*
X290330D01*
G01X290520Y92590D02*
X289890D01*
G01X290070Y92380D02*
X291210D01*
G01X291200Y92290D02*
X290170D01*
G01X289310Y90160D02*
X289270Y89980D01*
G01X289310Y90170D02*
Y90160D01*
G01X289420Y90480D02*
X289310Y90170D01*
G01X289430Y90490D02*
X289420Y90480D01*
G01X289640Y90800D02*
X289430Y90490D01*
G01X289650Y90810D02*
X289640Y90800D01*
G01X289890Y91030D02*
X289650Y90810D01*
G01X289900Y91030D02*
X289890D01*
G01X290020Y91110D02*
X289900Y91030D01*
G01X290030Y91120D02*
X290020Y91110D01*
G01X290090Y91150D02*
X290030Y91120D01*
G01X290250Y91220D02*
X290090Y91150D01*
G01X289260Y89880D02*
X290020D01*
G01X290060Y89490D02*
X284510D01*
G01X290050Y89510D02*
X290060Y89490D01*
G01X290000Y89770D02*
X290050Y89510D01*
G01X290000Y89780D02*
Y89770D01*
G01Y89800D02*
Y89780D01*
G01X284550Y89180D02*
X290290D01*
G01X290210Y89250D02*
X290150Y89340D01*
G01X290220Y89240D02*
X290210Y89250D01*
G01X290230Y89230D02*
X290220Y89240D01*
G01X290070Y89480D02*
X290060Y89490D01*
G01X290150Y89350D02*
X290070Y89480D01*
G01X290020Y89680D02*
X289260D01*
G01X289290Y90090D02*
X290060D01*
G01X290050Y90060D02*
X290000Y89800D01*
G01X290060Y90080D02*
X290050Y90060D01*
G01X290280Y89810D02*
X290290Y89830D01*
G01X290230Y90340D02*
X290450Y90500D01*
G01X290220Y90330D02*
X290230Y90340D01*
G01X290210Y90310D02*
X290220Y90330D01*
G01X290070Y90100D02*
X290210Y90310D01*
G01X290060Y90080D02*
X290070Y90100D01*
G01X290290Y90380D02*
X289390D01*
G01X289350Y90290D02*
X290190D01*
G01X290120Y90180D02*
X289310D01*
G01X289490Y90590D02*
X290750D01*
G01X290160Y91180D02*
X291830D01*
G01X291920Y91090D02*
X289980D01*
G01X289740Y90880D02*
X292110D01*
G01X292290Y90680D02*
X289570D01*
G01X290150Y89290D02*
X290190D01*
G01X290230Y89230D02*
X290450Y89070D01*
G01X290020Y88490D02*
X291570D01*
G01X291730Y88590D02*
X289840D01*
G01X289400Y89020D02*
X285800D01*
G01X289480Y88990D02*
X289400Y89020D01*
G01X289490Y88980D02*
X289480Y88990D01*
G01X289490Y88970D02*
Y88980D01*
G01X289530Y88900D02*
X289490Y88970D01*
G01X289540Y88900D02*
X289530D01*
G01X289550Y88890D02*
X289540Y88900D01*
G01X289620Y88790D02*
X289550Y88890D01*
G01X289630Y88780D02*
X289620Y88790D01*
G01X289860Y88560D02*
X289630Y88780D01*
G01Y88790D02*
X291970D01*
G01X289880Y88550D02*
X289860Y88560D01*
G01X290680Y88250D02*
X291020Y88260D01*
G01X290670Y88250D02*
X290680D01*
G01X290660D02*
X290670D01*
G01X290500Y88270D02*
X290660Y88250D01*
G01X290480Y88270D02*
X290500D01*
G01X289880Y88550D02*
X290480Y88270D01*
G01X291130Y88290D02*
X290460D01*
G01Y89060D02*
X290450Y89070D01*
G01X290480Y89060D02*
X290460D01*
G01X290650Y89000D02*
X290480Y89060D01*
G01X290870Y88990D02*
X290890D01*
G01X290740D02*
X290870D01*
G01X290670Y89000D02*
X290740Y88990D01*
G01X290650Y89000D02*
X290670D01*
G01X290310Y89620D02*
X290280Y89810D01*
G01X290320Y89590D02*
X290310Y89620D01*
G01X290490Y89370D02*
X290320Y89590D01*
G01X290510Y89360D02*
X290490Y89370D01*
G01X290680Y89280D02*
X290510Y89360D01*
G01X290690Y89280D02*
X290680D01*
G01X290730Y89270D02*
X290690Y89280D01*
G01X290790Y89270D02*
X290730D01*
G01X290810D02*
X290790D01*
G01X290840Y90300D02*
X290850D01*
G01X290750D02*
X290840D01*
G01X290730Y90290D02*
X290750Y90300D01*
G01X290420Y90130D02*
X290730Y90290D01*
G01X290400Y90110D02*
X290420Y90130D01*
G01X290290Y89830D02*
X290400Y90110D01*
G01X290460Y90510D02*
X290450Y90500D01*
G01X290480Y90510D02*
X290460D01*
G01X290650Y90570D02*
X290480Y90510D01*
G01X290670Y90570D02*
X290650D01*
G01X290740Y90580D02*
X290670Y90570D01*
G01X290760Y90590D02*
X290740Y90580D01*
G01X290820Y90590D02*
X290760D01*
G01X290850Y90580D02*
X290820Y90590D01*
G01X290430Y90490D02*
X289430D01*
G01X290340Y89970D02*
X291280D01*
G01X291300Y89770D02*
X290290D01*
G01X290340Y89570D02*
X291250D01*
G01X291070Y89370D02*
X290500D01*
G01X290810Y89270D02*
X290940Y89290D01*
G01X291140Y90160D02*
X290490D01*
G01X290890Y90580D02*
X291090Y90530D01*
G01X290850Y90580D02*
X290890D01*
G01X290340Y91250D02*
X290250Y91220D01*
G01X290350Y91260D02*
X290340Y91250D01*
G01X290490Y91290D02*
X290350Y91260D01*
G01X290570Y91310D02*
X290490Y91290D01*
G01X290350Y92090D02*
X289250Y93270D01*
G01X290610Y91810D02*
X290350Y92090D01*
G01X290640Y91760D02*
X290610Y91810D01*
G01X290670Y91610D02*
X290640Y91760D01*
G01X290680Y91590D02*
X290670Y91610D01*
G01X290680Y91570D02*
Y91590D01*
G01X290660Y91400D02*
X290680Y91570D01*
G01X290660Y91390D02*
Y91400D01*
G01X290570Y91310D02*
X290660Y91390D01*
G01X289790Y92680D02*
X290430D01*
G01X290750Y92580D02*
X291260Y98810D01*
G01X290690Y92500D02*
X290750Y92580D01*
G01X290580Y92520D02*
X290690Y92500D01*
G01X290350Y98790D02*
X290330Y98760D01*
G01X290990Y98790D02*
X290350D01*
G01D02*
X291160Y99630D01*
G01X290740Y99180D02*
X293000D01*
G01Y98990D02*
X290550D01*
G01X290250Y98680D02*
X290890D01*
G01X290700Y98490D02*
X286700D01*
G01Y98290D02*
X290510D01*
G01X290310Y98090D02*
X286700D01*
G01X290920Y94590D02*
X291380D01*
G01X291370Y94380D02*
X290900D01*
G01X290880Y94180D02*
X291350D01*
G01X291340Y93990D02*
X290870D01*
G01X290850Y93790D02*
X291320D01*
G01X291310Y93590D02*
X290840D01*
G01X290820Y93380D02*
X291290D01*
G01X291270Y93180D02*
X290810D01*
G01X290790Y92990D02*
X291250D01*
G01X291240Y92790D02*
X290770D01*
G01X290750Y92590D02*
X291220D01*
G01X291180Y92090D02*
X290350D01*
G01X290540Y91880D02*
X291180D01*
G01X291360Y91680D02*
X290660D01*
G01X290670Y91490D02*
X291550D01*
G01X290500Y102980D02*
X290220Y103060D01*
G01X290510Y102970D02*
X290500Y102980D01*
G01X290620Y102940D02*
X290510Y102970D01*
G01X290620Y102930D02*
Y102940D01*
G01X290730Y102890D02*
X290620Y102930D01*
G01X290740Y102880D02*
X290730Y102890D01*
G01X291600Y102880D02*
X290740D01*
G01X290460Y102990D02*
X291490D01*
G01X290100Y103090D02*
X291350D01*
G01Y102330D02*
X291260Y102280D01*
G01X291340Y102430D02*
X291350Y102330D01*
G01X291270Y102540D02*
X291340Y102430D01*
G01X291250Y102560D02*
X291270Y102540D01*
G01X290950Y102780D02*
X291250Y102560D01*
G01X290940Y102790D02*
X290950Y102780D01*
G01X290930Y102790D02*
X290940D01*
G01X290740Y102880D02*
X290930Y102790D01*
G01X291270Y102290D02*
X292990D01*
G01X292970Y102490D02*
X291310D01*
G01X291080Y102680D02*
X292890D01*
G01X293000Y100680D02*
X291220D01*
G01X291190Y99660D02*
X291160Y99630D01*
G01X291220Y99720D02*
X291190Y99660D01*
G01X291220Y100740D02*
Y99720D01*
G01X291120Y99590D02*
X291790D01*
G01X291960Y99790D02*
X291220D01*
G01Y99990D02*
X292150D01*
G01X292340Y100180D02*
X291220D01*
G01Y100290D02*
X293000D01*
G01Y100490D02*
X291220D01*
G01X291330Y100820D02*
X291430Y100920D01*
G01X291260Y100820D02*
X291330D01*
G01X291220Y100780D02*
X291260Y100820D01*
G01X291220Y100740D02*
Y100780D01*
G01X290930Y99380D02*
X293000D01*
G01X291720Y98680D02*
X291250D01*
G01X291090Y98890D02*
X287880Y95560D01*
G01X291200Y98910D02*
X291090Y98890D01*
G01X291260Y98810D02*
X291200Y98910D01*
G01X290980Y95380D02*
X291450D01*
G01X291460Y95490D02*
X290990D01*
G01X291010Y95680D02*
X291480D01*
G01X291490Y95880D02*
X291030D01*
G01X291040Y96090D02*
X291510D01*
G01X291520Y96290D02*
X291060D01*
G01X291070Y96490D02*
X291540D01*
G01X291560Y96680D02*
X291090D01*
G01X291110Y96880D02*
X291570D01*
G01X291590Y97090D02*
X291120D01*
G01X291140Y97290D02*
X291610D01*
G01X291620Y97490D02*
X291160D01*
G01X291170Y97680D02*
X291640D01*
G01X291650Y97880D02*
X291190D01*
G01X291200Y98090D02*
X291670D01*
G01X291690Y98290D02*
X291220D01*
G01X291240Y98490D02*
X291700D01*
G01X291090Y98880D02*
X290450D01*
G01X290970Y95180D02*
X291440D01*
G01X291420Y94990D02*
X290950D01*
G01X290940Y94790D02*
X291400D01*
G01X291390Y94680D02*
X290930D01*
G01X290910Y94490D02*
X291380D01*
G01X291360Y94290D02*
X290890D01*
G01X290880Y94090D02*
X291350D01*
G01X291330Y93880D02*
X290860D01*
G01X290850Y93680D02*
X291310D01*
G01X291300Y93490D02*
X290830D01*
G01X290810Y93290D02*
X291280D01*
G01X291260Y93090D02*
X290800D01*
G01X290780Y92880D02*
X291250D01*
G01X291230Y92680D02*
X290760D01*
G01X291220Y92490D02*
X289980D01*
G01X290260Y92180D02*
X291190D01*
G01X291180Y91990D02*
X290450D01*
G01X290620Y91790D02*
X291260D01*
G01X291200Y91850D02*
X292160Y90830D01*
G01X292480Y90490D02*
X291150D01*
G01X291130Y90510D02*
X291090Y90530D01*
G01X291130Y90510D02*
X291440Y90250D01*
G01X291210Y90070D02*
X290380D01*
G01X290300Y89870D02*
X291290D01*
G01X291100Y90200D02*
X290850Y90300D01*
G01X291120Y90190D02*
X291100Y90200D01*
G01X291270Y89990D02*
X291120Y90190D01*
G01X291280Y89960D02*
X291270Y89990D01*
G01X290940Y90270D02*
X290670D01*
G01X290960Y89290D02*
X290940D01*
G01X291180Y89430D02*
X290960Y89290D01*
G01X291190Y89450D02*
X291180Y89430D01*
G01X291300Y89680D02*
X291190Y89450D01*
G01X291310Y89700D02*
X291300Y89680D01*
G01X291280Y89960D02*
X291310Y89700D01*
G01X291150Y89090D02*
X292170D01*
G01X291030Y88260D02*
X291020D01*
G01X291320Y88330D02*
X291030Y88260D01*
G01X291330Y88340D02*
X291320Y88330D01*
G01X291840Y88650D02*
X291330Y88340D01*
G01X291090Y89040D02*
X291130Y89060D01*
G01X290890Y88990D02*
X291090Y89040D01*
G01X291200Y89470D02*
X290420D01*
G01X290300Y89660D02*
X291300D01*
G01X291190Y91870D02*
X291170Y91940D01*
G01X291200Y91860D02*
X291190Y91870D01*
G01X291200Y91850D02*
Y91860D01*
G01X292210Y103040D02*
X292220D01*
G01X292100Y103010D02*
X292210Y103040D01*
G01X292090Y103010D02*
X292100D01*
G01X291960Y102960D02*
X292090Y103010D01*
G01X291960Y102950D02*
Y102960D01*
G01X291900Y102920D02*
X291960Y102950D01*
G01X291880Y102900D02*
X291900Y102920D01*
G01X291820Y102850D02*
X291880Y102900D01*
G01X291800Y102830D02*
X291820Y102850D01*
G01X291660Y102830D02*
X291800D01*
G01X291480Y103000D02*
X291660Y102830D01*
G01X291470Y103010D02*
X291480Y103000D01*
G01X290970Y103320D02*
X291470Y103010D01*
G01X292030Y102990D02*
X292550D01*
G01X292600Y101680D02*
X291440D01*
G01X291490Y101630D02*
X291430Y100920D01*
G01X291400Y100880D02*
X291950D01*
G01X292240Y101610D02*
X292270Y101600D01*
G01X292160Y101620D02*
X292240Y101610D01*
G01X292090Y101640D02*
X292160Y101620D01*
G01X292080Y101640D02*
X292090D01*
G01X291950Y101550D02*
X292080Y101640D01*
G01X291900Y100940D02*
X291950Y101550D01*
G01X292000Y100830D02*
X291900Y100940D01*
G01X292000Y101590D02*
X291490D01*
G01X291390Y101740D02*
X284040D01*
G01X291490Y101630D02*
X291390Y101740D01*
G01X291030Y99490D02*
X291850D01*
G01X291820Y99640D02*
X292370Y100220D01*
G01X291790Y99590D02*
X291820Y99640D01*
G01X291790Y99550D02*
Y99590D01*
G01X291890Y99440D02*
X291790Y99550D01*
G01X292250Y100090D02*
X291220D01*
G01Y99880D02*
X292050D01*
G01X291860Y99680D02*
X291200D01*
G01X291220Y98880D02*
X291750D01*
G01X291740Y98870D02*
X291170Y91940D01*
G01X291450Y91590D02*
X290680D01*
G01X290650Y91380D02*
X291640D01*
G01X291730Y91290D02*
X290460D01*
G01X289850Y90990D02*
X292010D01*
G01X292200Y90790D02*
X289630D01*
G01X289480Y88990D02*
X292110D01*
G01X291930Y88740D02*
X291840Y88650D01*
G01X291990Y88810D02*
X291930Y88740D01*
G01X292120Y89000D02*
X291990Y88810D01*
G01X291880Y88680D02*
X289730D01*
G01X289550Y88880D02*
X292040D01*
G01X292240Y89250D02*
X292300Y89420D01*
G01X292200Y89150D02*
X292240Y89250D01*
G01X292200Y89140D02*
Y89150D01*
G01X292130Y89010D02*
X292200Y89140D01*
G01X292120Y89000D02*
X292130Y89010D01*
G01X292290Y89380D02*
X291475D01*
G01X291480D02*
X291540D01*
G01X291440Y89320D02*
X291130Y89060D01*
G01X291470Y89370D02*
X291440Y89320D01*
G01X291270Y89180D02*
X292220D01*
G01X292250Y89290D02*
X291460D01*
G01X291470Y90200D02*
X291440Y90250D01*
G01X291590Y89810D02*
X291470Y90200D01*
G01X291590Y89750D02*
Y89810D01*
G01X291470Y89370D02*
X291590Y89750D01*
G01X291400Y90290D02*
X292660D01*
G01X292850Y90090D02*
X291510D01*
G01X291570Y89880D02*
X293030D01*
G01X292330Y89680D02*
X291570D01*
G01X291510Y89490D02*
X292310D01*
G01X291400Y88380D02*
X290240D01*
G01X290940Y94880D02*
X291410D01*
G01X291430Y95090D02*
X290960D01*
G01X290980Y95290D02*
X291440D01*
G01X291470Y95590D02*
X291000D01*
G01X291010Y95790D02*
X291480D01*
G01X291500Y95990D02*
X291030D01*
G01X291050Y96180D02*
X291510D01*
G01X291530Y96380D02*
X291070D01*
G01X291080Y96590D02*
X291550D01*
G01X291570Y96790D02*
X291100D01*
G01X291110Y96990D02*
X291580D01*
G01X291600Y97180D02*
X291130D01*
G01X291150Y97380D02*
X291610D01*
G01X291630Y97590D02*
X291160D01*
G01X291180Y97790D02*
X291640D01*
G01X291660Y97990D02*
X291200D01*
G01X291210Y98180D02*
X291680D01*
G01X291700Y98380D02*
X291230D01*
G01X291240Y98590D02*
X291710D01*
G01X291730Y98790D02*
X291260D01*
G01X291740Y98870D02*
X291830Y98960D01*
G01X292160Y100820D02*
X292280D01*
G01X292000Y100830D02*
X292160Y100820D01*
G01X291910Y100990D02*
X291440D01*
G01X291450Y101090D02*
X291920D01*
G01Y101180D02*
X291460D01*
G01Y101290D02*
X291930D01*
G01X291940Y101380D02*
X291470D01*
G01X291480Y101490D02*
X291950D01*
G01X291860Y102880D02*
X292720D01*
G01X292830Y102790D02*
X290940D01*
G01X291220Y102590D02*
X292940D01*
G01X292980Y102380D02*
X291350D01*
G01X292840Y101880D02*
X282730D01*
G01Y102090D02*
X292940D01*
G01X292960Y98960D02*
X291830D01*
G01X291890Y99440D02*
X292440D01*
G01X293000Y99290D02*
X290830D01*
G01X290640Y99090D02*
X293000D01*
G01Y100380D02*
X291220D01*
G01Y100590D02*
X293000D01*
G01Y100790D02*
X291220D01*
G01X292380Y90590D02*
X290830D01*
G01X291270Y90380D02*
X292570D01*
G01X292750Y90180D02*
X291480D01*
G01X291530Y89990D02*
X292940D01*
G01X292320Y89590D02*
X291540D01*
G01X291590Y89790D02*
X292400D01*
G01X295970Y86740D02*
X292160Y90830D01*
G01X278700Y86720D02*
X284120Y92330D01*
G01X278670Y86690D02*
X278700Y86720D01*
G01X278680Y86670D02*
X278670Y86690D01*
G01X278990Y86400D02*
X278680Y86670D01*
G01X279020Y86390D02*
X278990Y86400D01*
G01X279040D02*
X279020Y86390D01*
G01X284160Y91700D02*
X279040Y86400D01*
G01X279120Y86490D02*
X278890D01*
G01X278770Y86590D02*
X279220D01*
G01X279320Y86680D02*
X278670D01*
G01X278760Y86790D02*
X279420D01*
G01X279510Y86880D02*
X278860D01*
G01X278950Y86990D02*
X279610D01*
G01X279700Y87090D02*
X279050D01*
G01X279140Y87180D02*
X279800D01*
G01X279900Y87290D02*
X279240D01*
G01X279340Y87380D02*
X279990D01*
G01X280090Y87490D02*
X279440D01*
G01X279530Y87590D02*
X280190D01*
G01X280280Y87680D02*
X279630D01*
G01X279730Y87790D02*
X280380D01*
G01X280480Y87880D02*
X279820D01*
G01X279920Y87990D02*
X280570D01*
G01X278370Y105600D02*
X278400Y105620D01*
G01X278370Y105060D02*
Y105600D01*
G01X278380Y105040D02*
X278370Y105060D01*
G01X278430Y104930D02*
X278380Y105040D01*
G01X278440Y104920D02*
X278430Y104930D01*
G01X278370Y105590D02*
X278430D01*
G01X278370Y105490D02*
X278520D01*
G01X278610Y105380D02*
X278370D01*
G01Y105290D02*
X278710D01*
G01X278800Y105180D02*
X278370D01*
G01Y105090D02*
X278890D01*
G01X278990Y104990D02*
X278400D01*
G01X278470Y104880D02*
X279080D01*
G01X279170Y104790D02*
X278560D01*
G01X278650Y104680D02*
X279260D01*
G01X279360Y104590D02*
X278750D01*
G01X278840Y104490D02*
X279450D01*
G01X279540Y104380D02*
X278930D01*
G01X279020Y104290D02*
X279640D01*
G01X279730Y104180D02*
X279120D01*
G01X279210Y104090D02*
X279820D01*
G01X279920Y103990D02*
X279300D01*
G01X279400Y103880D02*
X280010D01*
G01X280100Y103790D02*
X279490D01*
G01X279580Y103680D02*
X280200D01*
G01X280290Y103590D02*
X279680D01*
G01X279770Y103490D02*
X280380D01*
G01X280480Y103380D02*
X279860D01*
G01X279950Y103290D02*
X280570D01*
G01X280660Y103180D02*
X280050D01*
G01X284410Y103670D02*
X284440Y103690D01*
G01X284400Y103640D02*
X284410Y103670D01*
G01X284400Y103440D02*
Y103640D01*
G01X284390Y103400D02*
X284400Y103440D01*
G01X284370Y103350D02*
X284390Y103400D01*
G01X284320Y103290D02*
X284370Y103350D01*
G01X284230Y103250D02*
X284320Y103290D01*
G01X284440Y103680D02*
X285270D01*
G01X284400Y103490D02*
X287290D01*
G01X287280Y103290D02*
X284300D01*
G01X286650D02*
X286760Y103180D01*
G01X286380Y103260D02*
X286650Y103290D01*
G01X286100Y103230D02*
X286380Y103260D01*
G01X285980Y103220D02*
X286100Y103230D01*
G01X285880Y103200D02*
X285980Y103220D01*
G01X285630Y103160D02*
X285880Y103200D01*
G01X285620Y103160D02*
X285630D01*
G01X285530Y103140D02*
X285620Y103160D01*
G01X285520Y103140D02*
X285530D01*
G01X285260Y103690D02*
X284440D01*
G01X285280Y103680D02*
X285260Y103690D01*
G01X285310Y103670D02*
X285280Y103680D01*
G01X285340Y103650D02*
X285310Y103670D01*
G01X285420Y103630D02*
X285340Y103650D01*
G01X285440Y103640D02*
X285420Y103630D01*
G01X285680Y103680D02*
X285440Y103640D01*
G01X286180Y103750D02*
X285680Y103680D01*
G01X286300Y103760D02*
X286180Y103750D01*
G01X286360Y103760D02*
X286300D01*
G01X286520Y103780D02*
X286360Y103760D01*
G01X286660Y103790D02*
X286520Y103780D01*
G01X284120Y103180D02*
X285770D01*
G01X289330Y103790D02*
X286640D01*
G01X286660D02*
X286760Y103890D01*
G01X286750Y103180D02*
X289380D01*
G01X288850Y103400D02*
Y103360D01*
G01X288750Y103500D02*
X288850Y103400D01*
G01X287310Y103500D02*
X288750D01*
G01X287210Y103400D02*
X287310Y103500D01*
G01X287210Y103360D02*
Y103400D01*
G01X287310Y103250D02*
X287210Y103360D01*
G01X288750Y103250D02*
X287310D01*
G01X288850Y103360D02*
X288750Y103250D01*
G01X288850Y103380D02*
X290820D01*
G01X290530Y103490D02*
X288760D01*
G01X286760Y103920D02*
Y103890D01*
G01X286800Y103960D02*
X286760Y103920D01*
G01X289250Y103960D02*
X286800D01*
G01X289300Y103920D02*
X289250Y103960D01*
G01X289300Y103820D02*
Y103920D01*
G01X286750Y103880D02*
X289300D01*
G01X287210Y103380D02*
X284380D01*
G01X284400Y103590D02*
X290160D01*
G01X289380Y103720D02*
X289300Y103820D01*
G01X289430Y103720D02*
X289380D01*
G01X289990Y103630D02*
X289430Y103720D01*
G01X290170Y103590D02*
X289990Y103630D01*
G01X289610Y103680D02*
X285740D01*
G01X289520Y103200D02*
X289810Y103150D01*
G01X289490Y103200D02*
X289520D01*
G01X289410Y103220D02*
X289490Y103200D01*
G01X289600Y103180D02*
X291190D01*
G01X290290Y103550D02*
X290170Y103590D01*
G01X290400Y103530D02*
X290290Y103550D01*
G01X290640Y103450D02*
X290400Y103530D01*
G01X290750Y103410D02*
X290640Y103450D01*
G01X290810Y103390D02*
X290750Y103410D01*
G01X291030Y103290D02*
X288780D01*
G01X290960Y103330D02*
X290810Y103390D01*
G01X290970Y103320D02*
X290960Y103330D01*
G01X292220Y103040D02*
X292280Y103050D01*
G01X292220Y89290D02*
X292250D01*
G01X292350Y103050D02*
X292280D01*
G01X292360Y103040D02*
X292350Y103050D01*
G01X292620Y102970D02*
X292360Y103040D01*
G01X292630Y102960D02*
X292620Y102970D01*
G01X292830Y102790D02*
X292630Y102960D01*
G01X292840Y102780D02*
X292830Y102790D01*
G01X292960Y102550D02*
X292840Y102780D01*
G01X292970Y102530D02*
X292960Y102550D01*
G01X292990Y102250D02*
X292970Y102530D01*
G01X292990Y102240D02*
Y102250D01*
G01X292910Y101980D02*
X292990Y102240D01*
G01X292900Y101970D02*
X292910Y101980D01*
G01X292740Y101770D02*
X292900Y101970D01*
G01X292730Y101750D02*
X292740Y101770D01*
G01X292500Y101630D02*
X292730Y101750D01*
G01X292480Y101630D02*
X292500D01*
G01X292360Y101610D02*
X292480Y101630D01*
G01X292350Y101610D02*
X292360D01*
G01X292290Y101600D02*
X292350Y101610D01*
G01X292270Y101600D02*
X292290D01*
G01X293250Y101790D02*
X293880D01*
G01X293980Y101880D02*
X293350D01*
G01X293440Y101990D02*
X294080D01*
G01X294170Y102090D02*
X293540D01*
G01X293640Y102180D02*
X294270D01*
G01X294360Y102290D02*
X293740D01*
G01X293830Y102380D02*
X294460D01*
G01X294560Y102490D02*
X293930D01*
G01X294030Y102590D02*
X294660D01*
G01X294850Y102790D02*
X294220D01*
G01X294410Y102990D02*
X295040D01*
G01X293790Y101680D02*
X293160D01*
G01X293060Y101590D02*
X293690D01*
G01X293590Y101490D02*
X292960D01*
G01X292860Y101380D02*
X293500D01*
G01X293400Y101290D02*
X292770D01*
G01X292670Y101180D02*
X293310D01*
G01X293210Y101090D02*
X292580D01*
G01X292480Y100990D02*
X293110D01*
G01X293000Y98980D02*
X292960Y98960D01*
G01X293000Y98990D02*
Y98980D01*
G01Y100810D02*
Y98990D01*
G01Y100820D02*
Y100810D01*
G01X293030Y100900D02*
X293000Y100820D01*
G01X292480Y100240D02*
X292370Y100220D01*
G01X292540Y100140D02*
X292480Y100240D01*
G01X292540Y99540D02*
Y100140D01*
G01X292440Y99440D02*
X292540Y99540D01*
G01X292510Y100180D02*
X293000D01*
G01Y100090D02*
X292540D01*
G01Y99990D02*
X293000D01*
G01Y99880D02*
X292540D01*
G01Y99790D02*
X293000D01*
G01Y99680D02*
X292540D01*
G01Y99590D02*
X293000D01*
G01Y99490D02*
X292490D01*
G01X292280Y100820D02*
X292350Y100850D01*
G01X292380Y100880D02*
X293020D01*
G01X293130Y89790D02*
X292440D01*
G01X292300Y89440D02*
Y89420D01*
G01X292340Y89710D02*
X292300Y89440D01*
G01X292400Y89790D02*
X292340Y89710D01*
G01X292400Y89790D02*
X292510Y89770D01*
G01X292590Y89680D02*
X293220D01*
G01X293310Y89590D02*
X292680D01*
G01X292770Y89490D02*
X293410D01*
G01X293460Y89380D02*
X293500D01*
G01X293510D02*
X292870D01*
G01X292960Y89290D02*
X293595D01*
G01X293590D02*
X293540D01*
G01X293695Y89180D02*
X293050D01*
G01X293140Y89090D02*
X293780D01*
G01X293870Y88990D02*
X293235D01*
G01X293335Y88880D02*
X293970D01*
G01X294060Y88790D02*
X293420D01*
G01X293525Y88680D02*
X294150D01*
G01X294250Y88590D02*
X293610D01*
G01X293700Y88490D02*
X294340D01*
G01X294430Y88380D02*
X293790D01*
G01X293880Y88290D02*
X294530D01*
G01X294710Y88090D02*
X294070D01*
G01X293980Y88180D02*
X294620D01*
G01X294800Y87990D02*
X294160D01*
G01X294260Y87880D02*
X294900D01*
G01X294990Y87790D02*
X294350D01*
G01X294440Y87680D02*
X295080D01*
G01X295180Y87590D02*
X294530D01*
G01X294630Y87490D02*
X295270D01*
G01X295360Y87380D02*
X294720D01*
G01X294810Y87290D02*
X295460D01*
G01X295550Y87180D02*
X294910D01*
G01X295000Y87090D02*
X295640D01*
G01X295830Y86880D02*
X295190D01*
G01X295370Y86680D02*
X295980D01*
G01X295640Y86400D02*
X295660Y86380D01*
G01X292510Y89770D02*
X295640Y86400D01*
G01X295560Y86490D02*
X295780D01*
G01X292350Y100850D02*
X296930Y105590D01*
G01X296960Y104980D02*
X293030Y100900D01*
G01X294120Y102680D02*
X294750D01*
G01X294940Y102880D02*
X294310D01*
G01X294510Y103090D02*
X295140D01*
G01X295740Y86990D02*
X295090D01*
G01X295280Y86790D02*
X295920D01*
G01X295690Y86400D02*
X295660Y86380D01*
G01X295980Y86690D02*
X295690Y86400D01*
G01X295990Y86710D02*
X295980Y86690D01*
G01Y86720D02*
X295990Y86710D01*
G01X295970Y86740D02*
X295980Y86720D01*
G01X295460Y86590D02*
X295880D01*
G01X295240Y103180D02*
X294610D01*
G01X294700Y103290D02*
X295330D01*
G01X295430Y103380D02*
X294800D01*
G01X294900Y103490D02*
X295520D01*
G01X295620Y103590D02*
X294990D01*
G01X295180Y103790D02*
X295810D01*
G01X296010Y103990D02*
X295380D01*
G01X295570Y104180D02*
X296200D01*
G01X296100Y104090D02*
X295480D01*
G01X295670Y104290D02*
X296290D01*
G01X296390Y104380D02*
X295760D01*
G01X295860Y104490D02*
X296490D01*
G01X296590Y104590D02*
X295960D01*
G01X296050Y104680D02*
X296680D01*
G01X296780Y104790D02*
X296150D01*
G01X296250Y104880D02*
X296870D01*
G01X296980Y105090D02*
X296440D01*
G01X296970Y105010D02*
X296980Y105090D01*
G01X296960Y104980D02*
X296970Y105010D01*
G01X296350Y104990D02*
X296960D01*
G01X296980Y105580D02*
X296930Y105590D01*
G01X296980Y105090D02*
Y105580D01*
G01X296920Y105590D02*
X296960D01*
G01X296980Y105490D02*
X296830D01*
G01X296730Y105380D02*
X296980D01*
G01Y105290D02*
X296630D01*
G01X296540Y105180D02*
X296980D01*
G01X295910Y103880D02*
X295280D01*
G01X295090Y103680D02*
X295720D01*
G54D16*
G01X16751Y-179426D02*
Y-161926D01*
G01X25047D02*
X16751Y-172718D01*
G01X26357Y-179426D02*
X20462Y-167760D01*
G01X34032Y-179426D02*
Y-161926D01*
X44076Y-179426D01*
Y-161926D01*
G01X56554Y-179426D02*
X54807Y-179134D01*
X53279Y-177968D01*
X51969Y-176218D01*
X51095Y-174176D01*
X50659Y-171843D01*
Y-169509D01*
X51095Y-167176D01*
X51969Y-165134D01*
X53279Y-163385D01*
X54807Y-162218D01*
X56554Y-161926D01*
X58300Y-162218D01*
X59829Y-163385D01*
X61139Y-165134D01*
X62013Y-167176D01*
X62449Y-169509D01*
Y-171843D01*
X62013Y-174176D01*
X61139Y-176218D01*
X59829Y-177968D01*
X58300Y-179134D01*
X56554Y-179426D01*
G01X69469D02*
X78639Y-161926D01*
G01X69469D02*
X78639Y-179426D01*
G01X104687D02*
Y-161926D01*
X109927D01*
X111674Y-162801D01*
X112984Y-164843D01*
X113421Y-167176D01*
X112984Y-169509D01*
X111892Y-171259D01*
X109927Y-172135D01*
X104687D01*
G01X126554Y-179426D02*
X124807Y-179134D01*
X123279Y-177968D01*
X121969Y-176218D01*
X121095Y-174176D01*
X120659Y-171843D01*
Y-169509D01*
X121095Y-167176D01*
X121969Y-165134D01*
X123279Y-163385D01*
X124807Y-162218D01*
X126554Y-161926D01*
X128300Y-162218D01*
X129829Y-163385D01*
X131139Y-165134D01*
X132013Y-167176D01*
X132449Y-169509D01*
Y-171843D01*
X132013Y-174176D01*
X131139Y-176218D01*
X129829Y-177968D01*
X128300Y-179134D01*
X126554Y-179426D01*
G01X137504Y-161926D02*
X140560Y-179426D01*
X144054Y-161926D01*
X147547Y-179426D01*
X150604Y-161926D01*
G01X165921Y-179426D02*
X157187D01*
Y-161926D01*
X165921D01*
G01X162427Y-170384D02*
X157187D01*
G01X174687Y-179426D02*
Y-161926D01*
X180146D01*
X181892Y-162801D01*
X182984Y-163968D01*
X183421Y-166301D01*
X182984Y-168635D01*
X181674Y-170093D01*
X180146Y-170968D01*
X174687D01*
G01X180146D02*
X183421Y-179426D01*
G01X214054Y-161926D02*
Y-179426D01*
G01X209032Y-161926D02*
X219076D01*
G01X227187Y-179426D02*
Y-161926D01*
X232646D01*
X234392Y-162801D01*
X235484Y-163968D01*
X235921Y-166301D01*
X235484Y-168635D01*
X234174Y-170093D01*
X232646Y-170968D01*
X227187D01*
G01X232646D02*
X235921Y-179426D01*
G01X243595D02*
X249054Y-161926D01*
X254513Y-179426D01*
G01X252547Y-173301D02*
X245560D01*
G01X261532Y-179426D02*
Y-161926D01*
X271576Y-179426D01*
Y-161926D01*
G01X279469Y-177093D02*
X281216Y-178551D01*
X283181Y-179426D01*
X284927D01*
X286674Y-178551D01*
X287984Y-177093D01*
X288639Y-175051D01*
X288202Y-173010D01*
X287111Y-171259D01*
X285146Y-170093D01*
X282526Y-169509D01*
X280997Y-168343D01*
X280342Y-166301D01*
X280779Y-164259D01*
X281871Y-162801D01*
X283399Y-161926D01*
X284927D01*
X286456Y-162509D01*
X287766Y-163968D01*
G01X298934Y-161926D02*
X304174D01*
G01X301554D02*
Y-179426D01*
G01X298934D02*
X304174D01*
G01X319054Y-161926D02*
Y-179426D01*
G01X314032Y-161926D02*
X324076D01*
G01X333934D02*
X339174D01*
G01X336554D02*
Y-179426D01*
G01X333934D02*
X339174D01*
G01X354054D02*
X352307Y-179134D01*
X350779Y-177968D01*
X349469Y-176218D01*
X348595Y-174176D01*
X348159Y-171843D01*
Y-169509D01*
X348595Y-167176D01*
X349469Y-165134D01*
X350779Y-163385D01*
X352307Y-162218D01*
X354054Y-161926D01*
X355800Y-162218D01*
X357329Y-163385D01*
X358639Y-165134D01*
X359513Y-167176D01*
X359949Y-169509D01*
Y-171843D01*
X359513Y-174176D01*
X358639Y-176218D01*
X357329Y-177968D01*
X355800Y-179134D01*
X354054Y-179426D01*
G01X366532D02*
Y-161926D01*
X376576Y-179426D01*
Y-161926D01*
G01X408300Y-170093D02*
X409174Y-169218D01*
X409829Y-167760D01*
X410266Y-165717D01*
X409829Y-163968D01*
X408956Y-162801D01*
X407427Y-161926D01*
X401532D01*
Y-179426D01*
X408737D01*
X410266Y-178260D01*
X411139Y-176509D01*
X411576Y-174468D01*
X411139Y-172426D01*
X409829Y-170676D01*
X408300Y-170093D01*
X401532D01*
G01X424054Y-179426D02*
X422307Y-179134D01*
X420779Y-177968D01*
X419469Y-176218D01*
X418595Y-174176D01*
X418159Y-171843D01*
Y-169509D01*
X418595Y-167176D01*
X419469Y-165134D01*
X420779Y-163385D01*
X422307Y-162218D01*
X424054Y-161926D01*
X425800Y-162218D01*
X427329Y-163385D01*
X428639Y-165134D01*
X429513Y-167176D01*
X429949Y-169509D01*
Y-171843D01*
X429513Y-174176D01*
X428639Y-176218D01*
X427329Y-177968D01*
X425800Y-179134D01*
X424054Y-179426D01*
G01X436095D02*
X441554Y-161926D01*
X447013Y-179426D01*
G01X445047Y-173301D02*
X438060D01*
G01X454687Y-179426D02*
Y-161926D01*
X460146D01*
X461892Y-162801D01*
X462984Y-163968D01*
X463421Y-166301D01*
X462984Y-168635D01*
X461674Y-170093D01*
X460146Y-170968D01*
X454687D01*
G01X460146D02*
X463421Y-179426D01*
G01X471751D02*
Y-161926D01*
X476117D01*
X477864Y-162801D01*
X479174Y-163968D01*
X480266Y-165717D01*
X481139Y-167760D01*
X481357Y-170676D01*
X481139Y-173593D01*
X480266Y-175635D01*
X479174Y-177385D01*
X477864Y-178551D01*
X476117Y-179426D01*
X471751D01*
G01X208377Y-134426D02*
Y-116926D01*
X214054Y-131509D01*
X219731Y-116926D01*
Y-134426D01*
G01X231554D02*
X230244Y-134134D01*
X228934Y-132968D01*
X228060Y-130926D01*
X227624Y-128593D01*
X228060Y-126259D01*
X228934Y-124218D01*
X230244Y-123051D01*
X231554Y-122760D01*
X232864Y-123051D01*
X234174Y-124218D01*
X235047Y-126259D01*
X235266Y-128593D01*
X235047Y-130926D01*
X234174Y-132968D01*
X232864Y-134134D01*
X231554Y-134426D01*
G01X252984Y-116926D02*
Y-134426D01*
G01Y-131802D02*
X252111Y-133260D01*
X250800Y-134134D01*
X249272Y-134426D01*
X247526Y-133843D01*
X246216Y-132385D01*
X245342Y-130635D01*
X245124Y-128593D01*
X245342Y-126551D01*
X246216Y-124801D01*
X247526Y-123343D01*
X249272Y-122760D01*
X250800Y-123051D01*
X251892Y-123635D01*
X252984Y-124801D01*
G01X263279Y-126551D02*
X270266D01*
X269611Y-124509D01*
X268519Y-123343D01*
X266991Y-122760D01*
X265462Y-123051D01*
X264152Y-123926D01*
X263279Y-125968D01*
X262842Y-127718D01*
Y-129468D01*
X263279Y-131218D01*
X264371Y-132968D01*
X265681Y-134134D01*
X267209Y-134426D01*
X268737Y-133843D01*
X270266Y-132093D01*
G01X284054Y-134426D02*
Y-116926D01*
G01X536554Y-179426D02*
Y-161926D01*
X533934Y-165426D01*
G01Y-179426D02*
X539174D01*
G01X549906Y-164843D02*
X551216Y-163093D01*
X552744Y-162218D01*
X554491Y-161926D01*
X556674Y-162509D01*
X558202Y-163968D01*
X558639Y-165717D01*
X558421Y-167468D01*
X557547Y-168926D01*
X553181Y-171843D01*
X551216Y-173884D01*
X549906Y-176802D01*
X549469Y-179426D01*
X558639D01*
G01X566751Y-176802D02*
X568060Y-178260D01*
X569589Y-179134D01*
X571554Y-179426D01*
X573519Y-178843D01*
X575047Y-177676D01*
X576139Y-175635D01*
X576357Y-173301D01*
X575921Y-170968D01*
X574829Y-169509D01*
X573300Y-168343D01*
X571772Y-168051D01*
X570244Y-168343D01*
X568279Y-169509D01*
X568934Y-161926D01*
X574829D01*
G01X584906Y-164843D02*
X586216Y-163093D01*
X587744Y-162218D01*
X589491Y-161926D01*
X591674Y-162509D01*
X593202Y-163968D01*
X593639Y-165717D01*
X593421Y-167468D01*
X592547Y-168926D01*
X588181Y-171843D01*
X586216Y-173884D01*
X584906Y-176802D01*
X584469Y-179426D01*
X593639D01*
G01X601751Y-175926D02*
X603060Y-177968D01*
X604807Y-179134D01*
X606772Y-179426D01*
X608519Y-179134D01*
X610266Y-177676D01*
X611357Y-175926D01*
X611576Y-174176D01*
X611139Y-172135D01*
X609611Y-170676D01*
X608082Y-170093D01*
X606117D01*
G01X608082D02*
X609392Y-169218D01*
X610484Y-167760D01*
X610921Y-166010D01*
X610484Y-164259D01*
X609392Y-162801D01*
X607427Y-161926D01*
X605462Y-162218D01*
X603497Y-163385D01*
G01X523437Y-134426D02*
Y-116926D01*
X528677D01*
X530424Y-117801D01*
X531734Y-119843D01*
X532171Y-122176D01*
X531734Y-124509D01*
X530642Y-126259D01*
X528677Y-127135D01*
X523437D01*
G01X550107Y-118385D02*
X548797Y-117509D01*
X547269Y-116926D01*
X545522D01*
X543557Y-117801D01*
X542029Y-119259D01*
X540937Y-121010D01*
X540064Y-123926D01*
X539845Y-126551D01*
X540282Y-129176D01*
X540937Y-130926D01*
X542247Y-132676D01*
X543776Y-133843D01*
X545304Y-134426D01*
X546832D01*
X548361Y-133843D01*
X549671Y-132968D01*
X550763Y-131802D01*
G01X564550Y-125093D02*
X565424Y-124218D01*
X566079Y-122760D01*
X566516Y-120717D01*
X566079Y-118968D01*
X565206Y-117801D01*
X563677Y-116926D01*
X557782D01*
Y-134426D01*
X564987D01*
X566516Y-133260D01*
X567389Y-131509D01*
X567826Y-129468D01*
X567389Y-127426D01*
X566079Y-125676D01*
X564550Y-125093D01*
X557782D01*
G01X573754Y-140259D02*
X586854D01*
G01X592782Y-134426D02*
Y-116926D01*
X602826Y-134426D01*
Y-116926D01*
G01X615304Y-134426D02*
X613557Y-134134D01*
X612029Y-132968D01*
X610719Y-131218D01*
X609845Y-129176D01*
X609409Y-126843D01*
Y-124509D01*
X609845Y-122176D01*
X610719Y-120134D01*
X612029Y-118385D01*
X613557Y-117218D01*
X615304Y-116926D01*
X617050Y-117218D01*
X618579Y-118385D01*
X619889Y-120134D01*
X620763Y-122176D01*
X621199Y-124509D01*
Y-126843D01*
X620763Y-129176D01*
X619889Y-131218D01*
X618579Y-132968D01*
X617050Y-134134D01*
X615304Y-134426D01*
G01X697854Y-179426D02*
Y-161926D01*
X695234Y-165426D01*
G01Y-179426D02*
X700474D01*
G01X666145Y-116926D02*
X671604Y-134426D01*
X677063Y-116926D01*
G01X693471Y-134426D02*
X684737D01*
Y-116926D01*
X693471D01*
G01X689977Y-125384D02*
X684737D01*
G01X702237Y-134426D02*
Y-116926D01*
X707696D01*
X709442Y-117801D01*
X710534Y-118968D01*
X710971Y-121301D01*
X710534Y-123635D01*
X709224Y-125093D01*
X707696Y-125968D01*
X702237D01*
G01X707696D02*
X710971Y-134426D01*
G01X724104Y-135009D02*
X723667Y-134718D01*
Y-134134D01*
X724104Y-133843D01*
X724541Y-134134D01*
Y-134718D01*
X724104Y-135009D01*
G01X804054Y-161926D02*
Y-179426D01*
G01X799032Y-161926D02*
X809076D01*
G01X816969Y-177093D02*
X818716Y-178551D01*
X820681Y-179426D01*
X822427D01*
X824174Y-178551D01*
X825484Y-177093D01*
X826139Y-175051D01*
X825702Y-173010D01*
X824611Y-171259D01*
X822646Y-170093D01*
X820026Y-169509D01*
X818497Y-168343D01*
X817842Y-166301D01*
X818279Y-164259D01*
X819371Y-162801D01*
X820899Y-161926D01*
X822427D01*
X823956Y-162509D01*
X825266Y-163968D01*
G01X836434Y-161926D02*
X841674D01*
G01X839054D02*
Y-179426D01*
G01X836434D02*
X841674D01*
G01X852187Y-161926D02*
Y-179426D01*
X860921D01*
G01X869251D02*
Y-161926D01*
G01X877547D02*
X869251Y-172718D01*
G01X878857Y-179426D02*
X872962Y-167760D01*
G01X790937Y-116926D02*
Y-134426D01*
X799671D01*
G01X816734D02*
Y-122760D01*
G01Y-124801D02*
X815861Y-123635D01*
X814550Y-123051D01*
X813022Y-122760D01*
X811494Y-123343D01*
X810184Y-124509D01*
X809310Y-126259D01*
X808874Y-128593D01*
X809310Y-130926D01*
X810184Y-132676D01*
X811494Y-133843D01*
X813022Y-134426D01*
X814550Y-134134D01*
X815861Y-133260D01*
X816734Y-132093D01*
G01X825719Y-139676D02*
X827029Y-140259D01*
X828776Y-139676D01*
X829867Y-138510D01*
X830741Y-137051D01*
X832050Y-132385D01*
X834889Y-122760D01*
G01X827902D02*
X832050Y-132385D01*
G01X844529Y-126551D02*
X851516D01*
X850861Y-124509D01*
X849769Y-123343D01*
X848241Y-122760D01*
X846712Y-123051D01*
X845402Y-123926D01*
X844529Y-125968D01*
X844092Y-127718D01*
Y-129468D01*
X844529Y-131218D01*
X845621Y-132968D01*
X846931Y-134134D01*
X848459Y-134426D01*
X849987Y-133843D01*
X851516Y-132093D01*
G01X862247Y-134426D02*
Y-122760D01*
G01Y-125093D02*
X863339Y-123926D01*
X864431Y-123051D01*
X865959Y-122760D01*
X867050Y-123051D01*
X868361Y-123926D01*
G01X879529Y-132385D02*
X880621Y-133551D01*
X882149Y-134426D01*
X883459D01*
X884769Y-133843D01*
X885642Y-132968D01*
X886079Y-131802D01*
X885861Y-130051D01*
X884987Y-129176D01*
X881057Y-127426D01*
X880184Y-125384D01*
X880621Y-123926D01*
X881494Y-123051D01*
X882804Y-122760D01*
X884114Y-123051D01*
X885424Y-123926D01*
G01X924737Y-175926D02*
X925829Y-177676D01*
X927139Y-178843D01*
X928667Y-179426D01*
X930414Y-178843D01*
X931724Y-177676D01*
X933034Y-175926D01*
X933471Y-173593D01*
Y-161926D01*
G01X946604Y-179426D02*
X944857Y-179134D01*
X943329Y-177968D01*
X942019Y-176218D01*
X941145Y-174176D01*
X940709Y-171843D01*
Y-169509D01*
X941145Y-167176D01*
X942019Y-165134D01*
X943329Y-163385D01*
X944857Y-162218D01*
X946604Y-161926D01*
X948350Y-162218D01*
X949879Y-163385D01*
X951189Y-165134D01*
X952063Y-167176D01*
X952499Y-169509D01*
Y-171843D01*
X952063Y-174176D01*
X951189Y-176218D01*
X949879Y-177968D01*
X948350Y-179134D01*
X946604Y-179426D01*
G01X959519Y-177093D02*
X961266Y-178551D01*
X963231Y-179426D01*
X964977D01*
X966724Y-178551D01*
X968034Y-177093D01*
X968689Y-175051D01*
X968252Y-173010D01*
X967161Y-171259D01*
X965196Y-170093D01*
X962576Y-169509D01*
X961047Y-168343D01*
X960392Y-166301D01*
X960829Y-164259D01*
X961921Y-162801D01*
X963449Y-161926D01*
X964977D01*
X966506Y-162509D01*
X967816Y-163968D01*
G01X985971Y-179426D02*
X977237D01*
Y-161926D01*
X985971D01*
G01X982477Y-170384D02*
X977237D01*
G01X994737Y-179426D02*
Y-161926D01*
X999977D01*
X1001724Y-162801D01*
X1003034Y-164843D01*
X1003471Y-167176D01*
X1003034Y-169509D01*
X1001942Y-171259D01*
X999977Y-172135D01*
X994737D01*
G01X1012019Y-179426D02*
Y-161926D01*
G01X1021189D02*
Y-179426D01*
G01Y-170676D02*
X1012019D01*
G01X1047237Y-161926D02*
Y-179426D01*
X1055971D01*
G01X1063645D02*
X1069104Y-161926D01*
X1074563Y-179426D01*
G01X1072597Y-173301D02*
X1065610D01*
G01X1081801Y-161926D02*
Y-174468D01*
X1082674Y-177093D01*
X1084421Y-178843D01*
X1086604Y-179426D01*
X1088787Y-178843D01*
X1090534Y-177093D01*
X1091407Y-174468D01*
Y-161926D01*
G01X941801Y-134426D02*
Y-116926D01*
X946167D01*
X947914Y-117801D01*
X949224Y-118968D01*
X950316Y-120717D01*
X951189Y-122760D01*
X951407Y-125676D01*
X951189Y-128593D01*
X950316Y-130635D01*
X949224Y-132385D01*
X947914Y-133551D01*
X946167Y-134426D01*
X941801D01*
G01X960829Y-126551D02*
X967816D01*
X967161Y-124509D01*
X966069Y-123343D01*
X964541Y-122760D01*
X963012Y-123051D01*
X961702Y-123926D01*
X960829Y-125968D01*
X960392Y-127718D01*
Y-129468D01*
X960829Y-131218D01*
X961921Y-132968D01*
X963231Y-134134D01*
X964759Y-134426D01*
X966287Y-133843D01*
X967816Y-132093D01*
G01X978329Y-132385D02*
X979421Y-133551D01*
X980949Y-134426D01*
X982259D01*
X983569Y-133843D01*
X984442Y-132968D01*
X984879Y-131802D01*
X984661Y-130051D01*
X983787Y-129176D01*
X979857Y-127426D01*
X978984Y-125384D01*
X979421Y-123926D01*
X980294Y-123051D01*
X981604Y-122760D01*
X982914Y-123051D01*
X984224Y-123926D01*
G01X999104Y-122760D02*
Y-134426D01*
G01Y-118093D02*
X998667Y-117801D01*
Y-117218D01*
X999104Y-116926D01*
X999541Y-117218D01*
Y-117801D01*
X999104Y-118093D01*
G01X1013547Y-138801D02*
X1015076Y-139968D01*
X1016822Y-140259D01*
X1018350Y-139968D01*
X1019661Y-138510D01*
X1020534Y-136468D01*
Y-122760D01*
G01Y-125093D02*
X1019661Y-123926D01*
X1018350Y-123051D01*
X1016822Y-122760D01*
X1015076Y-123343D01*
X1013984Y-124509D01*
X1013110Y-126551D01*
X1012674Y-128593D01*
X1012892Y-130343D01*
X1013766Y-132385D01*
X1015076Y-133843D01*
X1016822Y-134426D01*
X1018132Y-134134D01*
X1019661Y-132968D01*
X1020534Y-131802D01*
G01X1030392Y-134426D02*
Y-122760D01*
G01Y-125676D02*
X1031266Y-124218D01*
X1032576Y-123051D01*
X1034322Y-122760D01*
X1035850Y-123051D01*
X1037161Y-124218D01*
X1037816Y-126259D01*
Y-134426D01*
G01X1048329Y-126551D02*
X1055316D01*
X1054661Y-124509D01*
X1053569Y-123343D01*
X1052041Y-122760D01*
X1050512Y-123051D01*
X1049202Y-123926D01*
X1048329Y-125968D01*
X1047892Y-127718D01*
Y-129468D01*
X1048329Y-131218D01*
X1049421Y-132968D01*
X1050731Y-134134D01*
X1052259Y-134426D01*
X1053787Y-133843D01*
X1055316Y-132093D01*
G01X1066047Y-134426D02*
Y-122760D01*
G01Y-125093D02*
X1067139Y-123926D01*
X1068231Y-123051D01*
X1069759Y-122760D01*
X1070850Y-123051D01*
X1072161Y-123926D01*
G01X1112804Y-179426D02*
Y-161926D01*
X1110184Y-165426D01*
G01Y-179426D02*
X1115424D01*
G01X1130304Y-161926D02*
X1128557Y-162509D01*
X1127247Y-163968D01*
X1126374Y-165717D01*
X1125719Y-168051D01*
X1125501Y-170676D01*
X1125719Y-173301D01*
X1126374Y-175635D01*
X1127247Y-177385D01*
X1128557Y-178843D01*
X1130304Y-179426D01*
X1132050Y-178843D01*
X1133361Y-177385D01*
X1134234Y-175635D01*
X1134889Y-173301D01*
X1135107Y-170676D01*
X1134889Y-168051D01*
X1134234Y-165717D01*
X1133361Y-163968D01*
X1132050Y-162509D01*
X1130304Y-161926D01*
G01X1143874Y-180009D02*
X1151734Y-161926D01*
G01X1165304Y-179426D02*
Y-161926D01*
X1162684Y-165426D01*
G01Y-179426D02*
X1167924D01*
G01X1179092Y-177385D02*
X1180621Y-178843D01*
X1182367Y-179426D01*
X1184114Y-178843D01*
X1185642Y-177093D01*
X1186734Y-174468D01*
X1187171Y-171843D01*
Y-168635D01*
X1186734Y-166010D01*
X1185642Y-163676D01*
X1184332Y-162509D01*
X1182804Y-161926D01*
X1181057Y-162509D01*
X1179747Y-163676D01*
X1178874Y-165426D01*
X1178437Y-167760D01*
X1178874Y-169801D01*
X1179966Y-171843D01*
X1181276Y-173010D01*
X1182804Y-173301D01*
X1184550Y-172718D01*
X1185861Y-171259D01*
X1187171Y-168635D01*
G01X1196374Y-180009D02*
X1204234Y-161926D01*
G01X1213656Y-164843D02*
X1214966Y-163093D01*
X1216494Y-162218D01*
X1218241Y-161926D01*
X1220424Y-162509D01*
X1221952Y-163968D01*
X1222389Y-165717D01*
X1222171Y-167468D01*
X1221297Y-168926D01*
X1216931Y-171843D01*
X1214966Y-173884D01*
X1213656Y-176802D01*
X1213219Y-179426D01*
X1222389D01*
G01X1235304Y-161926D02*
X1233557Y-162509D01*
X1232247Y-163968D01*
X1231374Y-165717D01*
X1230719Y-168051D01*
X1230501Y-170676D01*
X1230719Y-173301D01*
X1231374Y-175635D01*
X1232247Y-177385D01*
X1233557Y-178843D01*
X1235304Y-179426D01*
X1237050Y-178843D01*
X1238361Y-177385D01*
X1239234Y-175635D01*
X1239889Y-173301D01*
X1240107Y-170676D01*
X1239889Y-168051D01*
X1239234Y-165717D01*
X1238361Y-163968D01*
X1237050Y-162509D01*
X1235304Y-161926D01*
G01X1252804Y-179426D02*
Y-161926D01*
X1250184Y-165426D01*
G01Y-179426D02*
X1255424D01*
G01X1266156Y-164843D02*
X1267466Y-163093D01*
X1268994Y-162218D01*
X1270741Y-161926D01*
X1272924Y-162509D01*
X1274452Y-163968D01*
X1274889Y-165717D01*
X1274671Y-167468D01*
X1273797Y-168926D01*
X1269431Y-171843D01*
X1267466Y-173884D01*
X1266156Y-176802D01*
X1265719Y-179426D01*
X1274889D01*
G01X1160501Y-134426D02*
Y-116926D01*
X1164867D01*
X1166614Y-117801D01*
X1167924Y-118968D01*
X1169016Y-120717D01*
X1169889Y-122760D01*
X1170107Y-125676D01*
X1169889Y-128593D01*
X1169016Y-130635D01*
X1167924Y-132385D01*
X1166614Y-133551D01*
X1164867Y-134426D01*
X1160501D01*
G01X1186734D02*
Y-122760D01*
G01Y-124801D02*
X1185861Y-123635D01*
X1184550Y-123051D01*
X1183022Y-122760D01*
X1181494Y-123343D01*
X1180184Y-124509D01*
X1179310Y-126259D01*
X1178874Y-128593D01*
X1179310Y-130926D01*
X1180184Y-132676D01*
X1181494Y-133843D01*
X1183022Y-134426D01*
X1184550Y-134134D01*
X1185861Y-133260D01*
X1186734Y-132093D01*
G01X1200304Y-116926D02*
Y-134426D01*
G01X1197247Y-122760D02*
X1203361D01*
G01X1214529Y-126551D02*
X1221516D01*
X1220861Y-124509D01*
X1219769Y-123343D01*
X1218241Y-122760D01*
X1216712Y-123051D01*
X1215402Y-123926D01*
X1214529Y-125968D01*
X1214092Y-127718D01*
Y-129468D01*
X1214529Y-131218D01*
X1215621Y-132968D01*
X1216931Y-134134D01*
X1218459Y-134426D01*
X1219987Y-133843D01*
X1221516Y-132093D01*
G01X-6750Y307150D02*
Y307983D01*
X-6000D01*
X-5750Y307733D01*
X-5583Y307442D01*
X-5500Y307025D01*
X-5583Y306608D01*
X-5750Y306317D01*
X-6000Y306067D01*
X-6292Y305900D01*
X-6625Y305817D01*
X-6917D01*
X-7167Y305900D01*
X-7458Y306067D01*
X-7708Y306317D01*
X-7875Y306567D01*
X-8000Y306900D01*
Y307192D01*
X-7917Y307525D01*
X-7750Y307775D01*
G01X-5500Y309208D02*
X-8000D01*
Y310792D01*
G01X-6792Y310208D02*
Y309208D01*
G01X-5500Y313100D02*
X-8000D01*
X-7500Y312600D01*
G01X-5500D02*
Y313600D01*
G01X22575Y82000D02*
Y84500D01*
G01X24325D02*
Y82000D01*
G01Y83250D02*
X22575D01*
G01X25633Y82500D02*
X25883Y82208D01*
X26217Y82042D01*
X26592Y82000D01*
X26925Y82042D01*
X27258Y82250D01*
X27467Y82500D01*
X27508Y82750D01*
X27425Y83042D01*
X27133Y83250D01*
X26842Y83333D01*
X26467D01*
G01X26842D02*
X27092Y83458D01*
X27300Y83667D01*
X27383Y83917D01*
X27300Y84167D01*
X27092Y84375D01*
X26717Y84500D01*
X26342Y84458D01*
X25967Y84292D01*
G01X20208Y191767D02*
X20083Y191517D01*
X20000Y191225D01*
Y190892D01*
X20125Y190517D01*
X20333Y190225D01*
X20583Y190017D01*
X21000Y189850D01*
X21375Y189808D01*
X21750Y189892D01*
X22000Y190017D01*
X22250Y190267D01*
X22417Y190558D01*
X22500Y190850D01*
Y191142D01*
X22417Y191433D01*
X22292Y191683D01*
X22125Y191892D01*
G01X22000Y193033D02*
X22292Y193283D01*
X22458Y193617D01*
X22500Y193992D01*
X22458Y194325D01*
X22250Y194658D01*
X22000Y194867D01*
X21750Y194908D01*
X21458Y194825D01*
X21250Y194533D01*
X21167Y194242D01*
Y193867D01*
G01Y194242D02*
X21042Y194492D01*
X20833Y194700D01*
X20583Y194783D01*
X20333Y194700D01*
X20125Y194492D01*
X20000Y194117D01*
X20042Y193742D01*
X20208Y193367D01*
G01X22500Y197550D02*
X20000D01*
X21792Y196008D01*
Y198092D01*
G01X22208Y199442D02*
X22417Y199733D01*
X22500Y200067D01*
X22417Y200400D01*
X22167Y200692D01*
X21792Y200900D01*
X21417Y200983D01*
X20958D01*
X20583Y200900D01*
X20250Y200692D01*
X20083Y200442D01*
X20000Y200150D01*
X20083Y199817D01*
X20250Y199567D01*
X20500Y199400D01*
X20833Y199317D01*
X21125Y199400D01*
X21417Y199608D01*
X21583Y199858D01*
X21625Y200150D01*
X21542Y200483D01*
X21333Y200733D01*
X20958Y200983D01*
G01X15708Y191767D02*
X15583Y191517D01*
X15500Y191225D01*
Y190892D01*
X15625Y190517D01*
X15833Y190225D01*
X16083Y190017D01*
X16500Y189850D01*
X16875Y189808D01*
X17250Y189892D01*
X17500Y190017D01*
X17750Y190267D01*
X17917Y190558D01*
X18000Y190850D01*
Y191142D01*
X17917Y191433D01*
X17792Y191683D01*
X17625Y191892D01*
G01X17500Y193033D02*
X17792Y193283D01*
X17958Y193617D01*
X18000Y193992D01*
X17958Y194325D01*
X17750Y194658D01*
X17500Y194867D01*
X17250Y194908D01*
X16958Y194825D01*
X16750Y194533D01*
X16667Y194242D01*
Y193867D01*
G01Y194242D02*
X16542Y194492D01*
X16333Y194700D01*
X16083Y194783D01*
X15833Y194700D01*
X15625Y194492D01*
X15500Y194117D01*
X15542Y193742D01*
X15708Y193367D01*
G01X18000Y197550D02*
X15500D01*
X17292Y196008D01*
Y198092D01*
G01X18000Y200150D02*
X17958Y200442D01*
X17833Y200775D01*
X17625Y200983D01*
X17333Y201067D01*
X17042Y200983D01*
X16792Y200733D01*
X16667Y200358D01*
Y199942D01*
X16583Y199692D01*
X16375Y199483D01*
X16083Y199400D01*
X15792Y199525D01*
X15583Y199817D01*
X15500Y200150D01*
X15583Y200483D01*
X15792Y200775D01*
X16083Y200900D01*
X16375Y200817D01*
X16583Y200608D01*
X16667Y200358D01*
Y199942D01*
X16792Y199567D01*
X17042Y199317D01*
X17333Y199233D01*
X17625Y199317D01*
X17833Y199525D01*
X17958Y199858D01*
X18000Y200150D01*
G01X32017Y326500D02*
Y329000D01*
X33058D01*
X33392Y328875D01*
X33600Y328708D01*
X33683Y328375D01*
X33600Y328042D01*
X33350Y327833D01*
X33058Y327708D01*
X32017D01*
G01X33058D02*
X33683Y326500D01*
G01X35033Y327000D02*
X35283Y326708D01*
X35617Y326542D01*
X35992Y326500D01*
X36325Y326542D01*
X36658Y326750D01*
X36867Y327000D01*
X36908Y327250D01*
X36825Y327542D01*
X36533Y327750D01*
X36242Y327833D01*
X35867D01*
G01X36242D02*
X36492Y327958D01*
X36700Y328167D01*
X36783Y328417D01*
X36700Y328667D01*
X36492Y328875D01*
X36117Y329000D01*
X35742Y328958D01*
X35367Y328792D01*
G01X39050Y326500D02*
X39342Y326542D01*
X39675Y326667D01*
X39883Y326875D01*
X39967Y327167D01*
X39883Y327458D01*
X39633Y327708D01*
X39258Y327833D01*
X38842D01*
X38592Y327917D01*
X38383Y328125D01*
X38300Y328417D01*
X38425Y328708D01*
X38717Y328917D01*
X39050Y329000D01*
X39383Y328917D01*
X39675Y328708D01*
X39800Y328417D01*
X39717Y328125D01*
X39508Y327917D01*
X39258Y327833D01*
X38842D01*
X38467Y327708D01*
X38217Y327458D01*
X38133Y327167D01*
X38217Y326875D01*
X38425Y326667D01*
X38758Y326542D01*
X39050Y326500D01*
G01X41233Y326875D02*
X41483Y326667D01*
X41775Y326542D01*
X42150Y326500D01*
X42525Y326583D01*
X42817Y326750D01*
X43025Y327042D01*
X43067Y327375D01*
X42983Y327708D01*
X42775Y327917D01*
X42483Y328083D01*
X42192Y328125D01*
X41900Y328083D01*
X41525Y327917D01*
X41650Y329000D01*
X42775D01*
G01X32017Y322500D02*
Y325000D01*
X33058D01*
X33392Y324875D01*
X33600Y324708D01*
X33683Y324375D01*
X33600Y324042D01*
X33350Y323833D01*
X33058Y323708D01*
X32017D01*
G01X33058D02*
X33683Y322500D01*
G01X35033Y323000D02*
X35283Y322708D01*
X35617Y322542D01*
X35992Y322500D01*
X36325Y322542D01*
X36658Y322750D01*
X36867Y323000D01*
X36908Y323250D01*
X36825Y323542D01*
X36533Y323750D01*
X36242Y323833D01*
X35867D01*
G01X36242D02*
X36492Y323958D01*
X36700Y324167D01*
X36783Y324417D01*
X36700Y324667D01*
X36492Y324875D01*
X36117Y325000D01*
X35742Y324958D01*
X35367Y324792D01*
G01X39050Y322500D02*
X39342Y322542D01*
X39675Y322667D01*
X39883Y322875D01*
X39967Y323167D01*
X39883Y323458D01*
X39633Y323708D01*
X39258Y323833D01*
X38842D01*
X38592Y323917D01*
X38383Y324125D01*
X38300Y324417D01*
X38425Y324708D01*
X38717Y324917D01*
X39050Y325000D01*
X39383Y324917D01*
X39675Y324708D01*
X39800Y324417D01*
X39717Y324125D01*
X39508Y323917D01*
X39258Y323833D01*
X38842D01*
X38467Y323708D01*
X38217Y323458D01*
X38133Y323167D01*
X38217Y322875D01*
X38425Y322667D01*
X38758Y322542D01*
X39050Y322500D01*
G01X42650D02*
Y325000D01*
X41108Y323208D01*
X43192D01*
G01X33198Y335436D02*
Y331436D01*
X40598D01*
G01X58042Y367502D02*
X46142D01*
G01X58042Y375502D02*
Y367502D01*
G01X46142Y375502D02*
X58042D01*
G01X46142Y367502D02*
Y375502D01*
G01X47742Y371502D02*
X46142Y373102D01*
G01X47742Y371502D02*
X46142Y369902D01*
G01X16013Y373593D02*
Y376093D01*
X17054D01*
X17388Y375968D01*
X17596Y375801D01*
X17679Y375468D01*
X17596Y375135D01*
X17346Y374926D01*
X17054Y374801D01*
X16013D01*
G01X17054D02*
X17679Y373593D01*
G01X19029Y374093D02*
X19279Y373801D01*
X19613Y373635D01*
X19988Y373593D01*
X20321Y373635D01*
X20654Y373843D01*
X20863Y374093D01*
X20904Y374343D01*
X20821Y374635D01*
X20529Y374843D01*
X20238Y374926D01*
X19863D01*
G01X20238D02*
X20488Y375051D01*
X20696Y375260D01*
X20779Y375510D01*
X20696Y375760D01*
X20488Y375968D01*
X20113Y376093D01*
X19738Y376051D01*
X19363Y375885D01*
G01X23046Y373593D02*
X23338Y373635D01*
X23671Y373760D01*
X23879Y373968D01*
X23963Y374260D01*
X23879Y374551D01*
X23629Y374801D01*
X23254Y374926D01*
X22838D01*
X22588Y375010D01*
X22379Y375218D01*
X22296Y375510D01*
X22421Y375801D01*
X22713Y376010D01*
X23046Y376093D01*
X23379Y376010D01*
X23671Y375801D01*
X23796Y375510D01*
X23713Y375218D01*
X23504Y375010D01*
X23254Y374926D01*
X22838D01*
X22463Y374801D01*
X22213Y374551D01*
X22129Y374260D01*
X22213Y373968D01*
X22421Y373760D01*
X22754Y373635D01*
X23046Y373593D01*
G01X26146D02*
X26438Y373635D01*
X26771Y373760D01*
X26979Y373968D01*
X27063Y374260D01*
X26979Y374551D01*
X26729Y374801D01*
X26354Y374926D01*
X25938D01*
X25688Y375010D01*
X25479Y375218D01*
X25396Y375510D01*
X25521Y375801D01*
X25813Y376010D01*
X26146Y376093D01*
X26479Y376010D01*
X26771Y375801D01*
X26896Y375510D01*
X26813Y375218D01*
X26604Y375010D01*
X26354Y374926D01*
X25938D01*
X25563Y374801D01*
X25313Y374551D01*
X25229Y374260D01*
X25313Y373968D01*
X25521Y373760D01*
X25854Y373635D01*
X26146Y373593D01*
G01X28108Y376132D02*
Y372132D01*
X35508D01*
G01X15627Y366557D02*
Y369057D01*
X16668D01*
X17002Y368932D01*
X17210Y368765D01*
X17293Y368432D01*
X17210Y368099D01*
X16960Y367890D01*
X16668Y367765D01*
X15627D01*
G01X16668D02*
X17293Y366557D01*
G01X18643Y367057D02*
X18893Y366765D01*
X19227Y366599D01*
X19602Y366557D01*
X19935Y366599D01*
X20268Y366807D01*
X20477Y367057D01*
X20518Y367307D01*
X20435Y367599D01*
X20143Y367807D01*
X19852Y367890D01*
X19477D01*
G01X19852D02*
X20102Y368015D01*
X20310Y368224D01*
X20393Y368474D01*
X20310Y368724D01*
X20102Y368932D01*
X19727Y369057D01*
X19352Y369015D01*
X18977Y368849D01*
G01X22660Y366557D02*
X22952Y366599D01*
X23285Y366724D01*
X23493Y366932D01*
X23577Y367224D01*
X23493Y367515D01*
X23243Y367765D01*
X22868Y367890D01*
X22452D01*
X22202Y367974D01*
X21993Y368182D01*
X21910Y368474D01*
X22035Y368765D01*
X22327Y368974D01*
X22660Y369057D01*
X22993Y368974D01*
X23285Y368765D01*
X23410Y368474D01*
X23327Y368182D01*
X23118Y367974D01*
X22868Y367890D01*
X22452D01*
X22077Y367765D01*
X21827Y367515D01*
X21743Y367224D01*
X21827Y366932D01*
X22035Y366724D01*
X22368Y366599D01*
X22660Y366557D01*
G01X25052Y366849D02*
X25343Y366640D01*
X25677Y366557D01*
X26010Y366640D01*
X26302Y366890D01*
X26510Y367265D01*
X26593Y367640D01*
Y368099D01*
X26510Y368474D01*
X26302Y368807D01*
X26052Y368974D01*
X25760Y369057D01*
X25427Y368974D01*
X25177Y368807D01*
X25010Y368557D01*
X24927Y368224D01*
X25010Y367932D01*
X25218Y367640D01*
X25468Y367474D01*
X25760Y367432D01*
X26093Y367515D01*
X26343Y367724D01*
X26593Y368099D01*
G01X28108Y370932D02*
Y366932D01*
X35508D01*
G01X35441Y348545D02*
X32941D01*
Y349586D01*
X33066Y349920D01*
X33233Y350128D01*
X33566Y350211D01*
X33899Y350128D01*
X34108Y349878D01*
X34233Y349586D01*
Y348545D01*
G01Y349586D02*
X35441Y350211D01*
G01Y352978D02*
X32941D01*
X34733Y351436D01*
Y353520D01*
G01X35441Y355578D02*
X35399Y355870D01*
X35274Y356203D01*
X35066Y356411D01*
X34774Y356495D01*
X34483Y356411D01*
X34233Y356161D01*
X34108Y355786D01*
Y355370D01*
X34024Y355120D01*
X33816Y354911D01*
X33524Y354828D01*
X33233Y354953D01*
X33024Y355245D01*
X32941Y355578D01*
X33024Y355911D01*
X33233Y356203D01*
X33524Y356328D01*
X33816Y356245D01*
X34024Y356036D01*
X34108Y355786D01*
Y355370D01*
X34233Y354995D01*
X34483Y354745D01*
X34774Y354661D01*
X35066Y354745D01*
X35274Y354953D01*
X35399Y355286D01*
X35441Y355578D01*
G01Y359178D02*
X32941D01*
X34733Y357636D01*
Y359720D01*
G01X45072Y371247D02*
X41072D01*
Y363847D01*
G01X34726Y382721D02*
X32226D01*
Y383762D01*
X32351Y384096D01*
X32518Y384304D01*
X32851Y384387D01*
X33184Y384304D01*
X33393Y384054D01*
X33518Y383762D01*
Y382721D01*
G01Y383762D02*
X34726Y384387D01*
G01Y387154D02*
X32226D01*
X34018Y385612D01*
Y387696D01*
G01X34726Y389754D02*
X34684Y390046D01*
X34559Y390379D01*
X34351Y390587D01*
X34059Y390671D01*
X33768Y390587D01*
X33518Y390337D01*
X33393Y389962D01*
Y389546D01*
X33309Y389296D01*
X33101Y389087D01*
X32809Y389004D01*
X32518Y389129D01*
X32309Y389421D01*
X32226Y389754D01*
X32309Y390087D01*
X32518Y390379D01*
X32809Y390504D01*
X33101Y390421D01*
X33309Y390212D01*
X33393Y389962D01*
Y389546D01*
X33518Y389171D01*
X33768Y388921D01*
X34059Y388837D01*
X34351Y388921D01*
X34559Y389129D01*
X34684Y389462D01*
X34726Y389754D01*
G01X33684Y392062D02*
X33393Y392354D01*
X33226Y392604D01*
X33143Y392937D01*
X33226Y393229D01*
X33393Y393437D01*
X33643Y393604D01*
X33934Y393646D01*
X34184Y393604D01*
X34434Y393437D01*
X34643Y393187D01*
X34726Y392896D01*
X34643Y392562D01*
X34393Y392271D01*
X34018Y392104D01*
X33601Y392062D01*
X33059Y392146D01*
X32768Y392271D01*
X32476Y392479D01*
X32268Y392771D01*
X32226Y393062D01*
X32309Y393354D01*
X32518Y393562D01*
G01X45159Y379285D02*
X41159D01*
Y371885D01*
G01X33198Y339936D02*
Y335936D01*
X40598D01*
G01X57352Y392774D02*
X53352D01*
Y385374D01*
G01X59000Y334517D02*
X56500D01*
Y335558D01*
X56625Y335892D01*
X56792Y336100D01*
X57125Y336183D01*
X57458Y336100D01*
X57667Y335850D01*
X57792Y335558D01*
Y334517D01*
G01Y335558D02*
X59000Y336183D01*
G01X58500Y337533D02*
X58792Y337783D01*
X58958Y338117D01*
X59000Y338492D01*
X58958Y338825D01*
X58750Y339158D01*
X58500Y339367D01*
X58250Y339408D01*
X57958Y339325D01*
X57750Y339033D01*
X57667Y338742D01*
Y338367D01*
G01Y338742D02*
X57542Y338992D01*
X57333Y339200D01*
X57083Y339283D01*
X56833Y339200D01*
X56625Y338992D01*
X56500Y338617D01*
X56542Y338242D01*
X56708Y337867D01*
G01X57958Y340758D02*
X57667Y341050D01*
X57500Y341300D01*
X57417Y341633D01*
X57500Y341925D01*
X57667Y342133D01*
X57917Y342300D01*
X58208Y342342D01*
X58458Y342300D01*
X58708Y342133D01*
X58917Y341883D01*
X59000Y341592D01*
X58917Y341258D01*
X58667Y340967D01*
X58292Y340800D01*
X57875Y340758D01*
X57333Y340842D01*
X57042Y340967D01*
X56750Y341175D01*
X56542Y341467D01*
X56500Y341758D01*
X56583Y342050D01*
X56792Y342258D01*
G01X58708Y343942D02*
X58917Y344233D01*
X59000Y344567D01*
X58917Y344900D01*
X58667Y345192D01*
X58292Y345400D01*
X57917Y345483D01*
X57458D01*
X57083Y345400D01*
X56750Y345192D01*
X56583Y344942D01*
X56500Y344650D01*
X56583Y344317D01*
X56750Y344067D01*
X57000Y343900D01*
X57333Y343817D01*
X57625Y343900D01*
X57917Y344108D01*
X58083Y344358D01*
X58125Y344650D01*
X58042Y344983D01*
X57833Y345233D01*
X57458Y345483D01*
G01X55398Y350460D02*
X59398D01*
Y357860D01*
G01X62052Y392692D02*
X58052D01*
Y385292D01*
G01X49500Y334517D02*
X47000D01*
Y335558D01*
X47125Y335892D01*
X47292Y336100D01*
X47625Y336183D01*
X47958Y336100D01*
X48167Y335850D01*
X48292Y335558D01*
Y334517D01*
G01Y335558D02*
X49500Y336183D01*
G01X49000Y337533D02*
X49292Y337783D01*
X49458Y338117D01*
X49500Y338492D01*
X49458Y338825D01*
X49250Y339158D01*
X49000Y339367D01*
X48750Y339408D01*
X48458Y339325D01*
X48250Y339033D01*
X48167Y338742D01*
Y338367D01*
G01Y338742D02*
X48042Y338992D01*
X47833Y339200D01*
X47583Y339283D01*
X47333Y339200D01*
X47125Y338992D01*
X47000Y338617D01*
X47042Y338242D01*
X47208Y337867D01*
G01X49500Y342050D02*
X47000D01*
X48792Y340508D01*
Y342592D01*
G01X49000Y343733D02*
X49292Y343983D01*
X49458Y344317D01*
X49500Y344692D01*
X49458Y345025D01*
X49250Y345358D01*
X49000Y345567D01*
X48750Y345608D01*
X48458Y345525D01*
X48250Y345233D01*
X48167Y344942D01*
Y344567D01*
G01Y344942D02*
X48042Y345192D01*
X47833Y345400D01*
X47583Y345483D01*
X47333Y345400D01*
X47125Y345192D01*
X47000Y344817D01*
X47042Y344442D01*
X47208Y344067D01*
G01X46325Y350450D02*
X50325D01*
Y357850D01*
G01X54500Y334517D02*
X52000D01*
Y335558D01*
X52125Y335892D01*
X52292Y336100D01*
X52625Y336183D01*
X52958Y336100D01*
X53167Y335850D01*
X53292Y335558D01*
Y334517D01*
G01Y335558D02*
X54500Y336183D01*
G01X54000Y337533D02*
X54292Y337783D01*
X54458Y338117D01*
X54500Y338492D01*
X54458Y338825D01*
X54250Y339158D01*
X54000Y339367D01*
X53750Y339408D01*
X53458Y339325D01*
X53250Y339033D01*
X53167Y338742D01*
Y338367D01*
G01Y338742D02*
X53042Y338992D01*
X52833Y339200D01*
X52583Y339283D01*
X52333Y339200D01*
X52125Y338992D01*
X52000Y338617D01*
X52042Y338242D01*
X52208Y337867D01*
G01X54500Y342050D02*
X52000D01*
X53792Y340508D01*
Y342592D01*
G01X52417Y343858D02*
X52167Y344108D01*
X52042Y344400D01*
X52000Y344733D01*
X52083Y345150D01*
X52292Y345442D01*
X52542Y345525D01*
X52792Y345483D01*
X53000Y345317D01*
X53417Y344483D01*
X53708Y344108D01*
X54125Y343858D01*
X54500Y343775D01*
Y345525D01*
G01X50705Y350395D02*
X54705D01*
Y357795D01*
G01X53094Y392725D02*
X49094D01*
Y385325D01*
G01X28929Y350277D02*
X28804Y350027D01*
X28721Y349735D01*
Y349402D01*
X28846Y349027D01*
X29054Y348735D01*
X29304Y348527D01*
X29721Y348360D01*
X30096Y348318D01*
X30471Y348402D01*
X30721Y348527D01*
X30971Y348777D01*
X31138Y349068D01*
X31221Y349360D01*
Y349652D01*
X31138Y349943D01*
X31013Y350193D01*
X30846Y350402D01*
G01X30721Y351543D02*
X31013Y351793D01*
X31179Y352127D01*
X31221Y352502D01*
X31179Y352835D01*
X30971Y353168D01*
X30721Y353377D01*
X30471Y353418D01*
X30179Y353335D01*
X29971Y353043D01*
X29888Y352752D01*
Y352377D01*
G01Y352752D02*
X29763Y353002D01*
X29554Y353210D01*
X29304Y353293D01*
X29054Y353210D01*
X28846Y353002D01*
X28721Y352627D01*
X28763Y352252D01*
X28929Y351877D01*
G01X30846Y354643D02*
X31054Y354893D01*
X31179Y355185D01*
X31221Y355560D01*
X31138Y355935D01*
X30971Y356227D01*
X30679Y356435D01*
X30346Y356477D01*
X30013Y356393D01*
X29804Y356185D01*
X29638Y355893D01*
X29596Y355602D01*
X29638Y355310D01*
X29804Y354935D01*
X28721Y355060D01*
Y356185D01*
G01X31221Y358660D02*
X31179Y358952D01*
X31054Y359285D01*
X30846Y359493D01*
X30554Y359577D01*
X30263Y359493D01*
X30013Y359243D01*
X29888Y358868D01*
Y358452D01*
X29804Y358202D01*
X29596Y357993D01*
X29304Y357910D01*
X29013Y358035D01*
X28804Y358327D01*
X28721Y358660D01*
X28804Y358993D01*
X29013Y359285D01*
X29304Y359410D01*
X29596Y359327D01*
X29804Y359118D01*
X29888Y358868D01*
Y358452D01*
X30013Y358077D01*
X30263Y357827D01*
X30554Y357743D01*
X30846Y357827D01*
X31054Y358035D01*
X31179Y358368D01*
X31221Y358660D01*
G01X28208Y384767D02*
X28083Y384517D01*
X28000Y384225D01*
Y383892D01*
X28125Y383517D01*
X28333Y383225D01*
X28583Y383017D01*
X29000Y382850D01*
X29375Y382808D01*
X29750Y382892D01*
X30000Y383017D01*
X30250Y383267D01*
X30417Y383558D01*
X30500Y383850D01*
Y384142D01*
X30417Y384433D01*
X30292Y384683D01*
X30125Y384892D01*
G01X30000Y386033D02*
X30292Y386283D01*
X30458Y386617D01*
X30500Y386992D01*
X30458Y387325D01*
X30250Y387658D01*
X30000Y387867D01*
X29750Y387908D01*
X29458Y387825D01*
X29250Y387533D01*
X29167Y387242D01*
Y386867D01*
G01Y387242D02*
X29042Y387492D01*
X28833Y387700D01*
X28583Y387783D01*
X28333Y387700D01*
X28125Y387492D01*
X28000Y387117D01*
X28042Y386742D01*
X28208Y386367D01*
G01X30125Y389133D02*
X30333Y389383D01*
X30458Y389675D01*
X30500Y390050D01*
X30417Y390425D01*
X30250Y390717D01*
X29958Y390925D01*
X29625Y390967D01*
X29292Y390883D01*
X29083Y390675D01*
X28917Y390383D01*
X28875Y390092D01*
X28917Y389800D01*
X29083Y389425D01*
X28000Y389550D01*
Y390675D01*
G01X30500Y393067D02*
X29958Y393150D01*
X29500Y393275D01*
X29083Y393442D01*
X28625Y393650D01*
X28000Y393983D01*
Y392317D01*
G01X20575Y438000D02*
Y440500D01*
G01X22325D02*
Y438000D01*
G01Y439250D02*
X20575D01*
G01X23758Y440083D02*
X24008Y440333D01*
X24300Y440458D01*
X24633Y440500D01*
X25050Y440417D01*
X25342Y440208D01*
X25425Y439958D01*
X25383Y439708D01*
X25217Y439500D01*
X24383Y439083D01*
X24008Y438792D01*
X23758Y438375D01*
X23675Y438000D01*
X25425D01*
G01X64500Y398517D02*
X62000D01*
Y399558D01*
X62125Y399892D01*
X62292Y400100D01*
X62625Y400183D01*
X62958Y400100D01*
X63167Y399850D01*
X63292Y399558D01*
Y398517D01*
G01Y399558D02*
X64500Y400183D01*
G01X64000Y401533D02*
X64292Y401783D01*
X64458Y402117D01*
X64500Y402492D01*
X64458Y402825D01*
X64250Y403158D01*
X64000Y403367D01*
X63750Y403408D01*
X63458Y403325D01*
X63250Y403033D01*
X63167Y402742D01*
Y402367D01*
G01Y402742D02*
X63042Y402992D01*
X62833Y403200D01*
X62583Y403283D01*
X62333Y403200D01*
X62125Y402992D01*
X62000Y402617D01*
X62042Y402242D01*
X62208Y401867D01*
G01X64500Y405467D02*
X63958Y405550D01*
X63500Y405675D01*
X63083Y405842D01*
X62625Y406050D01*
X62000Y406383D01*
Y404717D01*
G01Y408650D02*
X62083Y408317D01*
X62292Y408067D01*
X62542Y407900D01*
X62875Y407775D01*
X63250Y407733D01*
X63625Y407775D01*
X63958Y407900D01*
X64208Y408067D01*
X64417Y408317D01*
X64500Y408650D01*
X64417Y408983D01*
X64208Y409233D01*
X63958Y409400D01*
X63625Y409525D01*
X63250Y409567D01*
X62875Y409525D01*
X62542Y409400D01*
X62292Y409233D01*
X62083Y408983D01*
X62000Y408650D01*
G01X60500Y398517D02*
X58000D01*
Y399558D01*
X58125Y399892D01*
X58292Y400100D01*
X58625Y400183D01*
X58958Y400100D01*
X59167Y399850D01*
X59292Y399558D01*
Y398517D01*
G01Y399558D02*
X60500Y400183D01*
G01X60000Y401533D02*
X60292Y401783D01*
X60458Y402117D01*
X60500Y402492D01*
X60458Y402825D01*
X60250Y403158D01*
X60000Y403367D01*
X59750Y403408D01*
X59458Y403325D01*
X59250Y403033D01*
X59167Y402742D01*
Y402367D01*
G01Y402742D02*
X59042Y402992D01*
X58833Y403200D01*
X58583Y403283D01*
X58333Y403200D01*
X58125Y402992D01*
X58000Y402617D01*
X58042Y402242D01*
X58208Y401867D01*
G01X60500Y406050D02*
X58000D01*
X59792Y404508D01*
Y406592D01*
G01X60500Y409150D02*
X58000D01*
X59792Y407608D01*
Y409692D01*
G01X54208Y400267D02*
X54083Y400017D01*
X54000Y399725D01*
Y399392D01*
X54125Y399017D01*
X54333Y398725D01*
X54583Y398517D01*
X55000Y398350D01*
X55375Y398308D01*
X55750Y398392D01*
X56000Y398517D01*
X56250Y398767D01*
X56417Y399058D01*
X56500Y399350D01*
Y399642D01*
X56417Y399933D01*
X56292Y400183D01*
X56125Y400392D01*
G01X56000Y401533D02*
X56292Y401783D01*
X56458Y402117D01*
X56500Y402492D01*
X56458Y402825D01*
X56250Y403158D01*
X56000Y403367D01*
X55750Y403408D01*
X55458Y403325D01*
X55250Y403033D01*
X55167Y402742D01*
Y402367D01*
G01Y402742D02*
X55042Y402992D01*
X54833Y403200D01*
X54583Y403283D01*
X54333Y403200D01*
X54125Y402992D01*
X54000Y402617D01*
X54042Y402242D01*
X54208Y401867D01*
G01X56500Y406050D02*
X54000D01*
X55792Y404508D01*
Y406592D01*
G01X56500Y409150D02*
X54000D01*
X55792Y407608D01*
Y409692D01*
G01X50208Y400267D02*
X50083Y400017D01*
X50000Y399725D01*
Y399392D01*
X50125Y399017D01*
X50333Y398725D01*
X50583Y398517D01*
X51000Y398350D01*
X51375Y398308D01*
X51750Y398392D01*
X52000Y398517D01*
X52250Y398767D01*
X52417Y399058D01*
X52500Y399350D01*
Y399642D01*
X52417Y399933D01*
X52292Y400183D01*
X52125Y400392D01*
G01X52000Y401533D02*
X52292Y401783D01*
X52458Y402117D01*
X52500Y402492D01*
X52458Y402825D01*
X52250Y403158D01*
X52000Y403367D01*
X51750Y403408D01*
X51458Y403325D01*
X51250Y403033D01*
X51167Y402742D01*
Y402367D01*
G01Y402742D02*
X51042Y402992D01*
X50833Y403200D01*
X50583Y403283D01*
X50333Y403200D01*
X50125Y402992D01*
X50000Y402617D01*
X50042Y402242D01*
X50208Y401867D01*
G01X52500Y406050D02*
X50000D01*
X51792Y404508D01*
Y406592D01*
G01X52125Y407733D02*
X52333Y407983D01*
X52458Y408275D01*
X52500Y408650D01*
X52417Y409025D01*
X52250Y409317D01*
X51958Y409525D01*
X51625Y409567D01*
X51292Y409483D01*
X51083Y409275D01*
X50917Y408983D01*
X50875Y408692D01*
X50917Y408400D01*
X51083Y408025D01*
X50000Y408150D01*
Y409275D01*
G01X113521Y-18528D02*
Y-14528D01*
X112721Y-15328D01*
G01Y-18528D02*
X114321D01*
G01X114167Y149500D02*
Y159500D01*
X118500Y151167D01*
X122833Y159500D01*
Y149500D01*
G01X124933D02*
X129100Y159500D01*
X133267Y149500D01*
G01X131767Y153000D02*
X126433D01*
G01X136033Y149500D02*
Y159500D01*
X139367D01*
X140700Y159000D01*
X141700Y158333D01*
X142533Y157333D01*
X143200Y156166D01*
X143367Y154500D01*
X143200Y152833D01*
X142533Y151667D01*
X141700Y150666D01*
X140700Y150000D01*
X139367Y149500D01*
X136033D01*
G01X153633D02*
X146967D01*
Y159500D01*
X153633D01*
G01X150967Y154667D02*
X146967D01*
G01X169500Y159500D02*
X173500D01*
G01X171500D02*
Y149500D01*
G01X169500D02*
X173500D01*
G01X178267D02*
Y159500D01*
X185933Y149500D01*
Y159500D01*
G01X203300D02*
Y149500D01*
G01X199467Y159500D02*
X207133D01*
G01X209733Y149500D02*
X213900Y159500D01*
X218067Y149500D01*
G01X216567Y153000D02*
X211233D01*
G01X222500Y159500D02*
X226500D01*
G01X224500D02*
Y149500D01*
G01X222500D02*
X226500D01*
G01X230100Y159500D02*
X232433Y149500D01*
X235100Y159500D01*
X237767Y149500D01*
X240100Y159500D01*
G01X241533Y149500D02*
X245700Y159500D01*
X249867Y149500D01*
G01X248367Y153000D02*
X243033D01*
G01X252467Y149500D02*
Y159500D01*
X260133Y149500D01*
Y159500D01*
G01X120000Y165500D02*
Y175500D01*
X113833Y168333D01*
X122167D01*
G01X128600Y165500D02*
X129767Y165667D01*
X131100Y166167D01*
X131933Y167000D01*
X132267Y168167D01*
X131933Y169333D01*
X130933Y170333D01*
X129433Y170833D01*
X127767D01*
X126767Y171167D01*
X125933Y172000D01*
X125600Y173167D01*
X126100Y174333D01*
X127266Y175167D01*
X128600Y175500D01*
X129933Y175167D01*
X131100Y174333D01*
X131600Y173167D01*
X131267Y172000D01*
X130433Y171167D01*
X129433Y170833D01*
X127767D01*
X126267Y170333D01*
X125267Y169333D01*
X124933Y168167D01*
X125267Y167000D01*
X126100Y166167D01*
X127433Y165667D01*
X128600Y165500D01*
G01X139200Y165167D02*
X138867Y165333D01*
Y165667D01*
X139200Y165833D01*
X139533Y165667D01*
Y165333D01*
X139200Y165167D01*
G01X146633Y169666D02*
X147800Y170833D01*
X148800Y171500D01*
X150133Y171833D01*
X151300Y171500D01*
X152133Y170833D01*
X152800Y169833D01*
X152967Y168667D01*
X152800Y167667D01*
X152133Y166666D01*
X151133Y165833D01*
X149967Y165500D01*
X148633Y165833D01*
X147467Y166833D01*
X146800Y168333D01*
X146633Y170000D01*
X146967Y172166D01*
X147467Y173333D01*
X148300Y174500D01*
X149467Y175333D01*
X150633Y175500D01*
X151800Y175167D01*
X152633Y174333D01*
G01X162400Y165500D02*
Y175500D01*
X156233Y168333D01*
X164567D01*
G01X166000Y175500D02*
X168333Y165500D01*
X171000Y175500D01*
X173667Y165500D01*
X176000Y175500D01*
G01X181600Y165500D02*
Y175500D01*
X179600Y173500D01*
G01Y165500D02*
X183600D01*
G01X188533Y167500D02*
X189533Y166333D01*
X190866Y165667D01*
X192367Y165500D01*
X193700Y165667D01*
X195033Y166500D01*
X195867Y167500D01*
X196033Y168500D01*
X195700Y169666D01*
X194533Y170500D01*
X193367Y170833D01*
X191867D01*
G01X193367D02*
X194367Y171333D01*
X195200Y172166D01*
X195533Y173167D01*
X195200Y174167D01*
X194367Y175000D01*
X192867Y175500D01*
X191367Y175333D01*
X189867Y174667D01*
G01X202800Y165167D02*
X202467Y165333D01*
Y165667D01*
X202800Y165833D01*
X203133Y165667D01*
Y165333D01*
X202800Y165167D01*
G01X213400Y175500D02*
X212066Y175167D01*
X211067Y174333D01*
X210400Y173333D01*
X209900Y172000D01*
X209733Y170500D01*
X209900Y169000D01*
X210400Y167667D01*
X211067Y166666D01*
X212066Y165833D01*
X213400Y165500D01*
X214733Y165833D01*
X215733Y166666D01*
X216400Y167667D01*
X216900Y169000D01*
X217067Y170500D01*
X216900Y172000D01*
X216400Y173333D01*
X215733Y174333D01*
X214733Y175167D01*
X213400Y175500D01*
G01X224000Y165500D02*
Y175500D01*
X222000Y173500D01*
G01Y165500D02*
X226000D01*
G01X234600D02*
Y175500D01*
X232600Y173500D01*
G01Y165500D02*
X236600D01*
G01X116033Y193167D02*
Y203167D01*
G01X122367D02*
X116033Y197000D01*
G01X123367Y193167D02*
X118867Y199833D01*
G01X126467Y193167D02*
Y203167D01*
X134133Y193167D01*
Y203167D01*
G01X140900Y193167D02*
X139566Y193334D01*
X138400Y194000D01*
X137400Y195000D01*
X136733Y196167D01*
X136400Y197500D01*
Y198834D01*
X136733Y200167D01*
X137400Y201334D01*
X138400Y202334D01*
X139566Y203000D01*
X140900Y203167D01*
X142233Y203000D01*
X143400Y202334D01*
X144400Y201334D01*
X145067Y200167D01*
X145400Y198834D01*
Y197500D01*
X145067Y196167D01*
X144400Y195000D01*
X143400Y194000D01*
X142233Y193334D01*
X140900Y193167D01*
G01X148000D02*
X155000Y203167D01*
G01X148000D02*
X155000Y193167D01*
G01X169367D02*
Y203167D01*
X173367D01*
X174700Y202667D01*
X175700Y201500D01*
X176033Y200167D01*
X175700Y198834D01*
X174867Y197834D01*
X173367Y197333D01*
X169367D01*
G01X183300Y193167D02*
X181966Y193334D01*
X180800Y194000D01*
X179800Y195000D01*
X179133Y196167D01*
X178800Y197500D01*
Y198834D01*
X179133Y200167D01*
X179800Y201334D01*
X180800Y202334D01*
X181966Y203000D01*
X183300Y203167D01*
X184633Y203000D01*
X185800Y202334D01*
X186800Y201334D01*
X187467Y200167D01*
X187800Y198834D01*
Y197500D01*
X187467Y196167D01*
X186800Y195000D01*
X185800Y194000D01*
X184633Y193334D01*
X183300Y193167D01*
G01X188900Y203167D02*
X191233Y193167D01*
X193900Y203167D01*
X196567Y193167D01*
X198900Y203167D01*
G01X207833Y193167D02*
X201167D01*
Y203167D01*
X207833D01*
G01X205167Y198334D02*
X201167D01*
G01X211767Y193167D02*
Y203167D01*
X215933D01*
X217267Y202667D01*
X218100Y202000D01*
X218433Y200667D01*
X218100Y199334D01*
X217100Y198500D01*
X215933Y198000D01*
X211767D01*
G01X215933D02*
X218433Y193167D01*
G01X236300Y203167D02*
Y193167D01*
G01X232467Y203167D02*
X240133D01*
G01X243567Y193167D02*
Y203167D01*
X247733D01*
X249067Y202667D01*
X249900Y202000D01*
X250233Y200667D01*
X249900Y199334D01*
X248900Y198500D01*
X247733Y198000D01*
X243567D01*
G01X247733D02*
X250233Y193167D01*
G01X253333D02*
X257500Y203167D01*
X261667Y193167D01*
G01X260167Y196667D02*
X254833D01*
G01X264267Y193167D02*
Y203167D01*
X271933Y193167D01*
Y203167D01*
G01X275200Y194500D02*
X276533Y193667D01*
X278033Y193167D01*
X279367D01*
X280700Y193667D01*
X281700Y194500D01*
X282200Y195667D01*
X281867Y196833D01*
X281033Y197834D01*
X279533Y198500D01*
X277533Y198834D01*
X276367Y199500D01*
X275867Y200667D01*
X276200Y201834D01*
X277033Y202667D01*
X278200Y203167D01*
X279367D01*
X280533Y202834D01*
X281533Y202000D01*
G01X287300Y203167D02*
X291300D01*
G01X289300D02*
Y193167D01*
G01X287300D02*
X291300D01*
G01X299900Y203167D02*
Y193167D01*
G01X296067Y203167D02*
X303733D01*
G01X308500D02*
X312500D01*
G01X310500D02*
Y193167D01*
G01X308500D02*
X312500D01*
G01X321100D02*
X319766Y193334D01*
X318600Y194000D01*
X317600Y195000D01*
X316933Y196167D01*
X316600Y197500D01*
Y198834D01*
X316933Y200167D01*
X317600Y201334D01*
X318600Y202334D01*
X319766Y203000D01*
X321100Y203167D01*
X322433Y203000D01*
X323600Y202334D01*
X324600Y201334D01*
X325267Y200167D01*
X325600Y198834D01*
Y197500D01*
X325267Y196167D01*
X324600Y195000D01*
X323600Y194000D01*
X322433Y193334D01*
X321100Y193167D01*
G01X327867D02*
Y203167D01*
X335533Y193167D01*
Y203167D01*
G01X354233Y198500D02*
X354900Y199000D01*
X355400Y199833D01*
X355733Y201000D01*
X355400Y202000D01*
X354733Y202667D01*
X353567Y203167D01*
X349067D01*
Y193167D01*
X354567D01*
X355733Y193834D01*
X356400Y194834D01*
X356733Y196000D01*
X356400Y197167D01*
X355400Y198167D01*
X354233Y198500D01*
X349067D01*
G01X363500Y193167D02*
X362166Y193334D01*
X361000Y194000D01*
X360000Y195000D01*
X359333Y196167D01*
X359000Y197500D01*
Y198834D01*
X359333Y200167D01*
X360000Y201334D01*
X361000Y202334D01*
X362166Y203000D01*
X363500Y203167D01*
X364833Y203000D01*
X366000Y202334D01*
X367000Y201334D01*
X367667Y200167D01*
X368000Y198834D01*
Y197500D01*
X367667Y196167D01*
X367000Y195000D01*
X366000Y194000D01*
X364833Y193334D01*
X363500Y193167D01*
G01X369933D02*
X374100Y203167D01*
X378267Y193167D01*
G01X376767Y196667D02*
X371433D01*
G01X381367Y193167D02*
Y203167D01*
X385533D01*
X386867Y202667D01*
X387700Y202000D01*
X388033Y200667D01*
X387700Y199334D01*
X386700Y198500D01*
X385533Y198000D01*
X381367D01*
G01X385533D02*
X388033Y193167D01*
G01X391633D02*
Y203167D01*
X394967D01*
X396300Y202667D01*
X397300Y202000D01*
X398133Y201000D01*
X398800Y199833D01*
X398967Y198167D01*
X398800Y196500D01*
X398133Y195334D01*
X397300Y194333D01*
X396300Y193667D01*
X394967Y193167D01*
X391633D01*
G01X118500Y179000D02*
Y189000D01*
X116500Y187000D01*
G01Y179000D02*
X120500D01*
G01X125933Y187333D02*
X126933Y188333D01*
X128100Y188833D01*
X129433Y189000D01*
X131100Y188667D01*
X132267Y187833D01*
X132600Y186833D01*
X132433Y185833D01*
X131767Y185000D01*
X128433Y183333D01*
X126933Y182167D01*
X125933Y180500D01*
X125600Y179000D01*
X132600D01*
G01X136033Y180500D02*
X137033Y179667D01*
X138200Y179167D01*
X139700Y179000D01*
X141200Y179333D01*
X142367Y180000D01*
X143200Y181167D01*
X143367Y182500D01*
X143033Y183833D01*
X142200Y184667D01*
X141033Y185333D01*
X139867Y185500D01*
X138700Y185333D01*
X137200Y184667D01*
X137700Y189000D01*
X142200D01*
G01X147133Y187333D02*
X148133Y188333D01*
X149300Y188833D01*
X150633Y189000D01*
X152300Y188667D01*
X153467Y187833D01*
X153800Y186833D01*
X153633Y185833D01*
X152967Y185000D01*
X149633Y183333D01*
X148133Y182167D01*
X147133Y180500D01*
X146800Y179000D01*
X153800D01*
G01X157233Y181000D02*
X158233Y179833D01*
X159566Y179167D01*
X161067Y179000D01*
X162400Y179167D01*
X163733Y180000D01*
X164567Y181000D01*
X164733Y182000D01*
X164400Y183166D01*
X163233Y184000D01*
X162067Y184333D01*
X160567D01*
G01X162067D02*
X163067Y184833D01*
X163900Y185666D01*
X164233Y186667D01*
X163900Y187667D01*
X163067Y188500D01*
X161567Y189000D01*
X160067Y188833D01*
X158567Y188167D01*
G01X169333Y182333D02*
X173667D01*
G01X182100Y179000D02*
Y189000D01*
X180100Y187000D01*
G01Y179000D02*
X184100D01*
G01X71000Y382483D02*
X72792D01*
X73167Y382650D01*
X73417Y382983D01*
X73500Y383400D01*
X73417Y383817D01*
X73167Y384150D01*
X72792Y384317D01*
X71000D01*
G01X73125Y385583D02*
X73333Y385833D01*
X73458Y386125D01*
X73500Y386500D01*
X73417Y386875D01*
X73250Y387167D01*
X72958Y387375D01*
X72625Y387417D01*
X72292Y387333D01*
X72083Y387125D01*
X71917Y386833D01*
X71875Y386542D01*
X71917Y386250D01*
X72083Y385875D01*
X71000Y386000D01*
Y387125D01*
G01X73500Y389600D02*
X71000D01*
X71500Y389100D01*
G01X73500D02*
Y390100D01*
G01X77808Y362163D02*
Y364663D01*
X78849D01*
X79183Y364538D01*
X79391Y364371D01*
X79474Y364038D01*
X79391Y363705D01*
X79141Y363496D01*
X78849Y363371D01*
X77808D01*
G01X78849D02*
X79474Y362163D01*
G01X82241D02*
Y364663D01*
X80699Y362871D01*
X82783D01*
G01X84841Y362163D02*
X85133Y362205D01*
X85466Y362330D01*
X85674Y362538D01*
X85758Y362830D01*
X85674Y363121D01*
X85424Y363371D01*
X85049Y363496D01*
X84633D01*
X84383Y363580D01*
X84174Y363788D01*
X84091Y364080D01*
X84216Y364371D01*
X84508Y364580D01*
X84841Y364663D01*
X85174Y364580D01*
X85466Y364371D01*
X85591Y364080D01*
X85508Y363788D01*
X85299Y363580D01*
X85049Y363496D01*
X84633D01*
X84258Y363371D01*
X84008Y363121D01*
X83924Y362830D01*
X84008Y362538D01*
X84216Y362330D01*
X84549Y362205D01*
X84841Y362163D01*
G01X87024Y362538D02*
X87274Y362330D01*
X87566Y362205D01*
X87941Y362163D01*
X88316Y362246D01*
X88608Y362413D01*
X88816Y362705D01*
X88858Y363038D01*
X88774Y363371D01*
X88566Y363580D01*
X88274Y363746D01*
X87983Y363788D01*
X87691Y363746D01*
X87316Y363580D01*
X87441Y364663D01*
X88566D01*
G01X71491Y363163D02*
Y367163D01*
X64091D01*
G01X77367Y379736D02*
Y382236D01*
X78408D01*
X78742Y382111D01*
X78950Y381944D01*
X79033Y381611D01*
X78950Y381278D01*
X78700Y381069D01*
X78408Y380944D01*
X77367D01*
G01X78408D02*
X79033Y379736D01*
G01X81800D02*
Y382236D01*
X80258Y380444D01*
X82342D01*
G01X84400Y379736D02*
X84692Y379778D01*
X85025Y379903D01*
X85233Y380111D01*
X85317Y380403D01*
X85233Y380694D01*
X84983Y380944D01*
X84608Y381069D01*
X84192D01*
X83942Y381153D01*
X83733Y381361D01*
X83650Y381653D01*
X83775Y381944D01*
X84067Y382153D01*
X84400Y382236D01*
X84733Y382153D01*
X85025Y381944D01*
X85150Y381653D01*
X85067Y381361D01*
X84858Y381153D01*
X84608Y381069D01*
X84192D01*
X83817Y380944D01*
X83567Y380694D01*
X83483Y380403D01*
X83567Y380111D01*
X83775Y379903D01*
X84108Y379778D01*
X84400Y379736D01*
G01X87417D02*
X87500Y380278D01*
X87625Y380736D01*
X87792Y381153D01*
X88000Y381611D01*
X88333Y382236D01*
X86667D01*
G01X64150Y380236D02*
Y376236D01*
X71550D01*
G01X77364Y375479D02*
Y377979D01*
X78405D01*
X78739Y377854D01*
X78947Y377687D01*
X79030Y377354D01*
X78947Y377021D01*
X78697Y376812D01*
X78405Y376687D01*
X77364D01*
G01X78405D02*
X79030Y375479D01*
G01X81797D02*
Y377979D01*
X80255Y376187D01*
X82339D01*
G01X84397Y375479D02*
X84689Y375521D01*
X85022Y375646D01*
X85230Y375854D01*
X85314Y376146D01*
X85230Y376437D01*
X84980Y376687D01*
X84605Y376812D01*
X84189D01*
X83939Y376896D01*
X83730Y377104D01*
X83647Y377396D01*
X83772Y377687D01*
X84064Y377896D01*
X84397Y377979D01*
X84730Y377896D01*
X85022Y377687D01*
X85147Y377396D01*
X85064Y377104D01*
X84855Y376896D01*
X84605Y376812D01*
X84189D01*
X83814Y376687D01*
X83564Y376437D01*
X83480Y376146D01*
X83564Y375854D01*
X83772Y375646D01*
X84105Y375521D01*
X84397Y375479D01*
G01X87497D02*
Y377979D01*
X86997Y377479D01*
G01Y375479D02*
X87997D01*
G01X64147Y375979D02*
Y371979D01*
X71547D01*
G01X77815Y366470D02*
Y368970D01*
X78856D01*
X79190Y368845D01*
X79398Y368678D01*
X79481Y368345D01*
X79398Y368012D01*
X79148Y367803D01*
X78856Y367678D01*
X77815D01*
G01X78856D02*
X79481Y366470D01*
G01X82248D02*
Y368970D01*
X80706Y367178D01*
X82790D01*
G01X84848Y366470D02*
X85140Y366512D01*
X85473Y366637D01*
X85681Y366845D01*
X85765Y367137D01*
X85681Y367428D01*
X85431Y367678D01*
X85056Y367803D01*
X84640D01*
X84390Y367887D01*
X84181Y368095D01*
X84098Y368387D01*
X84223Y368678D01*
X84515Y368887D01*
X84848Y368970D01*
X85181Y368887D01*
X85473Y368678D01*
X85598Y368387D01*
X85515Y368095D01*
X85306Y367887D01*
X85056Y367803D01*
X84640D01*
X84265Y367678D01*
X84015Y367428D01*
X83931Y367137D01*
X84015Y366845D01*
X84223Y366637D01*
X84556Y366512D01*
X84848Y366470D01*
G01X87948Y368970D02*
X87615Y368887D01*
X87365Y368678D01*
X87198Y368428D01*
X87073Y368095D01*
X87031Y367720D01*
X87073Y367345D01*
X87198Y367012D01*
X87365Y366762D01*
X87615Y366553D01*
X87948Y366470D01*
X88281Y366553D01*
X88531Y366762D01*
X88698Y367012D01*
X88823Y367345D01*
X88865Y367720D01*
X88823Y368095D01*
X88698Y368428D01*
X88531Y368678D01*
X88281Y368887D01*
X87948Y368970D01*
G01X64098Y371470D02*
Y367470D01*
X71498D01*
G01X70900Y396000D02*
Y393500D01*
G01X69942Y396000D02*
X71858D01*
G01X73167Y393500D02*
Y396000D01*
X74167D01*
X74500Y395875D01*
X74750Y395583D01*
X74833Y395250D01*
X74750Y394917D01*
X74542Y394667D01*
X74167Y394542D01*
X73167D01*
G01X76392Y393792D02*
X76683Y393583D01*
X77017Y393500D01*
X77350Y393583D01*
X77642Y393833D01*
X77850Y394208D01*
X77933Y394583D01*
Y395042D01*
X77850Y395417D01*
X77642Y395750D01*
X77392Y395917D01*
X77100Y396000D01*
X76767Y395917D01*
X76517Y395750D01*
X76350Y395500D01*
X76267Y395167D01*
X76350Y394875D01*
X76558Y394583D01*
X76808Y394417D01*
X77100Y394375D01*
X77433Y394458D01*
X77683Y394667D01*
X77933Y395042D01*
G01X68552Y398509D02*
X66052D01*
Y399550D01*
X66177Y399884D01*
X66344Y400092D01*
X66677Y400175D01*
X67010Y400092D01*
X67219Y399842D01*
X67344Y399550D01*
Y398509D01*
G01Y399550D02*
X68552Y400175D01*
G01X68052Y401525D02*
X68344Y401775D01*
X68510Y402109D01*
X68552Y402484D01*
X68510Y402817D01*
X68302Y403150D01*
X68052Y403359D01*
X67802Y403400D01*
X67510Y403317D01*
X67302Y403025D01*
X67219Y402734D01*
Y402359D01*
G01Y402734D02*
X67094Y402984D01*
X66885Y403192D01*
X66635Y403275D01*
X66385Y403192D01*
X66177Y402984D01*
X66052Y402609D01*
X66094Y402234D01*
X66260Y401859D01*
G01X68177Y404625D02*
X68385Y404875D01*
X68510Y405167D01*
X68552Y405542D01*
X68469Y405917D01*
X68302Y406209D01*
X68010Y406417D01*
X67677Y406459D01*
X67344Y406375D01*
X67135Y406167D01*
X66969Y405875D01*
X66927Y405584D01*
X66969Y405292D01*
X67135Y404917D01*
X66052Y405042D01*
Y406167D01*
G01X68052Y407725D02*
X68344Y407975D01*
X68510Y408309D01*
X68552Y408684D01*
X68510Y409017D01*
X68302Y409350D01*
X68052Y409559D01*
X67802Y409600D01*
X67510Y409517D01*
X67302Y409225D01*
X67219Y408934D01*
Y408559D01*
G01Y408934D02*
X67094Y409184D01*
X66885Y409392D01*
X66635Y409475D01*
X66385Y409392D01*
X66177Y409184D01*
X66052Y408809D01*
X66094Y408434D01*
X66260Y408059D01*
G01X175044Y-17728D02*
X175444Y-18195D01*
X175978Y-18461D01*
X176578Y-18528D01*
X177111Y-18461D01*
X177644Y-18128D01*
X177978Y-17728D01*
X178044Y-17328D01*
X177911Y-16861D01*
X177444Y-16528D01*
X176978Y-16395D01*
X176378D01*
G01X176978D02*
X177378Y-16195D01*
X177711Y-15861D01*
X177844Y-15461D01*
X177711Y-15061D01*
X177378Y-14728D01*
X176778Y-14528D01*
X176178Y-14595D01*
X175578Y-14861D01*
G01X143749Y-15195D02*
X144149Y-14795D01*
X144616Y-14595D01*
X145149Y-14528D01*
X145816Y-14661D01*
X146283Y-14995D01*
X146416Y-15395D01*
X146349Y-15795D01*
X146083Y-16128D01*
X144749Y-16795D01*
X144149Y-17261D01*
X143749Y-17928D01*
X143616Y-18528D01*
X146416D01*
G01X208806D02*
Y-14528D01*
X206339Y-17395D01*
X209673D01*
G01X269730Y-16861D02*
X270197Y-16395D01*
X270597Y-16128D01*
X271130Y-15995D01*
X271597Y-16128D01*
X271930Y-16395D01*
X272197Y-16795D01*
X272264Y-17261D01*
X272197Y-17661D01*
X271930Y-18061D01*
X271530Y-18395D01*
X271064Y-18528D01*
X270530Y-18395D01*
X270064Y-17995D01*
X269797Y-17395D01*
X269730Y-16728D01*
X269864Y-15861D01*
X270064Y-15395D01*
X270397Y-14928D01*
X270864Y-14595D01*
X271330Y-14528D01*
X271797Y-14661D01*
X272130Y-14995D01*
G01X238035Y-17928D02*
X238435Y-18261D01*
X238902Y-18461D01*
X239502Y-18528D01*
X240102Y-18395D01*
X240569Y-18128D01*
X240902Y-17661D01*
X240969Y-17128D01*
X240835Y-16595D01*
X240502Y-16261D01*
X240035Y-15995D01*
X239569Y-15928D01*
X239102Y-15995D01*
X238502Y-16261D01*
X238702Y-14528D01*
X240502D01*
G01X276585Y73780D02*
X278835D01*
G01X276585Y67900D02*
Y73780D01*
G01X278835Y67900D02*
X276585D01*
G01X277935Y70935D02*
X276585D01*
G01X282335Y69570D02*
Y73780D01*
G01X282105Y68685D02*
X282335Y69570D01*
G01X281655Y68100D02*
X282105Y68685D01*
G01X281090Y67900D02*
X281655Y68100D01*
G01X280525D02*
X281090Y67900D01*
G01X280075Y68685D02*
X280525Y68100D01*
G01X279850Y69570D02*
X280075Y68685D01*
G01X279850Y73780D02*
Y69570D01*
G01X288300Y67995D02*
X287855Y67900D01*
G01X288700Y68390D02*
X288300Y67995D01*
G01X289035Y68980D02*
X288700Y68390D01*
G01X289265Y69665D02*
X289035Y68980D01*
G01X289375Y70450D02*
X289265Y69665D01*
G01X289375Y71230D02*
Y70450D01*
G01X289265Y72015D02*
X289375Y71230D01*
G01X289035Y72700D02*
X289265Y72015D01*
G01X288700Y73290D02*
X289035Y72700D01*
G01X288300Y73685D02*
X288700Y73290D01*
G01X287855Y73780D02*
X288300Y73685D01*
G01X287405D02*
X287855Y73780D01*
G01X287005Y73290D02*
X287405Y73685D01*
G01X286670Y72700D02*
X287005Y73290D01*
G01X286440Y72015D02*
X286670Y72700D01*
G01X286330Y71230D02*
X286440Y72015D01*
G01X286330Y70450D02*
Y71230D01*
G01X286440Y69665D02*
X286330Y70450D01*
G01X286670Y68980D02*
X286440Y69665D01*
G01X287005Y68390D02*
X286670Y68980D01*
G01X287405Y67995D02*
X287005Y68390D01*
G01X287855Y67900D02*
X287405Y67995D01*
G01X290280Y67900D02*
Y71820D01*
G01X292190Y70640D02*
Y67900D01*
G01X292020Y71330D02*
X292190Y70640D01*
G01X291680Y71720D02*
X292020Y71330D01*
G01X291290Y71820D02*
X291680Y71720D01*
G01X290835D02*
X291290Y71820D01*
G01X290500Y71330D02*
X290835Y71720D01*
G01X290280Y70840D02*
X290500Y71330D01*
G01X309333Y72500D02*
Y77500D01*
X311417D01*
X312083Y77250D01*
X312500Y76917D01*
X312667Y76250D01*
X312500Y75583D01*
X312000Y75167D01*
X311417Y74917D01*
X309333D01*
G01X311417D02*
X312667Y72500D01*
G01X316600D02*
X315933Y72583D01*
X315350Y72917D01*
X314850Y73417D01*
X314517Y74000D01*
X314350Y74667D01*
Y75333D01*
X314517Y76000D01*
X314850Y76583D01*
X315350Y77083D01*
X315933Y77417D01*
X316600Y77500D01*
X317267Y77417D01*
X317850Y77083D01*
X318350Y76583D01*
X318683Y76000D01*
X318850Y75333D01*
Y74667D01*
X318683Y74000D01*
X318350Y73417D01*
X317850Y72917D01*
X317267Y72583D01*
X316600Y72500D01*
G01X320450D02*
Y77500D01*
G01X323950D02*
Y72500D01*
G01Y75000D02*
X320450D01*
G01X326050Y73167D02*
X326717Y72750D01*
X327467Y72500D01*
X328133D01*
X328800Y72750D01*
X329300Y73167D01*
X329550Y73750D01*
X329383Y74333D01*
X328967Y74833D01*
X328217Y75167D01*
X327217Y75333D01*
X326633Y75667D01*
X326383Y76250D01*
X326550Y76833D01*
X326967Y77250D01*
X327550Y77500D01*
X328133D01*
X328717Y77333D01*
X329217Y76917D01*
G01X340333Y75417D02*
X339750Y75750D01*
X339250Y75833D01*
X338583Y75667D01*
X338083Y75333D01*
X337750Y74750D01*
X337667Y74167D01*
X337750Y73583D01*
X338083Y73083D01*
X338583Y72667D01*
X339250Y72500D01*
X339833Y72667D01*
X340333Y73000D01*
G01X344600Y72500D02*
X344100Y72583D01*
X343600Y72917D01*
X343267Y73500D01*
X343100Y74167D01*
X343267Y74833D01*
X343600Y75417D01*
X344100Y75750D01*
X344600Y75833D01*
X345100Y75750D01*
X345600Y75417D01*
X345933Y74833D01*
X346017Y74167D01*
X345933Y73500D01*
X345600Y72917D01*
X345100Y72583D01*
X344600Y72500D01*
G01X347700D02*
Y75833D01*
G01Y74917D02*
X347950Y75333D01*
X348367Y75667D01*
X348950Y75833D01*
X349533Y75667D01*
X349950Y75333D01*
X350200Y74917D01*
Y72500D01*
G01Y74917D02*
X350450Y75333D01*
X350867Y75667D01*
X351450Y75833D01*
X352033Y75667D01*
X352450Y75333D01*
X352700Y74833D01*
Y72500D01*
G01X354300Y70833D02*
Y75833D01*
G01Y75083D02*
X354717Y75500D01*
X355133Y75750D01*
X355800Y75833D01*
X356383Y75750D01*
X356967Y75333D01*
X357217Y74750D01*
X357300Y74167D01*
X357217Y73583D01*
X356967Y73000D01*
X356467Y72667D01*
X355800Y72500D01*
X355217Y72583D01*
X354633Y72833D01*
X354300Y73167D01*
G01X361400Y72500D02*
Y77500D01*
G01X367000Y75833D02*
Y72500D01*
G01Y77167D02*
X366833Y77250D01*
Y77417D01*
X367000Y77500D01*
X367167Y77417D01*
Y77250D01*
X367000Y77167D01*
G01X374100Y72500D02*
Y75833D01*
G01Y75250D02*
X373767Y75583D01*
X373267Y75750D01*
X372683Y75833D01*
X372100Y75667D01*
X371600Y75333D01*
X371267Y74833D01*
X371100Y74167D01*
X371267Y73500D01*
X371600Y73000D01*
X372100Y72667D01*
X372683Y72500D01*
X373267Y72583D01*
X373767Y72833D01*
X374100Y73167D01*
G01X376783Y72500D02*
Y75833D01*
G01Y75000D02*
X377117Y75417D01*
X377617Y75750D01*
X378283Y75833D01*
X378867Y75750D01*
X379367Y75417D01*
X379617Y74833D01*
Y72500D01*
G01X385133Y75417D02*
X384550Y75750D01*
X384050Y75833D01*
X383383Y75667D01*
X382883Y75333D01*
X382550Y74750D01*
X382467Y74167D01*
X382550Y73583D01*
X382883Y73083D01*
X383383Y72667D01*
X384050Y72500D01*
X384633Y72667D01*
X385133Y73000D01*
G01X388150Y74750D02*
X390817D01*
X390567Y75333D01*
X390150Y75667D01*
X389567Y75833D01*
X388983Y75750D01*
X388483Y75500D01*
X388150Y74917D01*
X387983Y74417D01*
Y73917D01*
X388150Y73417D01*
X388567Y72917D01*
X389067Y72583D01*
X389650Y72500D01*
X390233Y72667D01*
X390817Y73167D01*
G01X294615Y67900D02*
Y73780D01*
G01X298445Y68585D02*
X299180Y71820D01*
G01X298105Y67020D02*
X298445Y68585D01*
G01X297885Y66525D02*
X298105Y67020D01*
G01X297600Y66135D02*
X297885Y66525D01*
G01X297150Y65940D02*
X297600Y66135D01*
G01X296810D02*
X297150Y65940D01*
G01X297380Y71820D02*
X298445Y68585D01*
G01X460708Y207767D02*
X460583Y207517D01*
X460500Y207225D01*
Y206892D01*
X460625Y206517D01*
X460833Y206225D01*
X461083Y206017D01*
X461500Y205850D01*
X461875Y205808D01*
X462250Y205892D01*
X462500Y206017D01*
X462750Y206267D01*
X462917Y206558D01*
X463000Y206850D01*
Y207142D01*
X462917Y207433D01*
X462792Y207683D01*
X462625Y207892D01*
G01X462500Y209033D02*
X462792Y209283D01*
X462958Y209617D01*
X463000Y209992D01*
X462958Y210325D01*
X462750Y210658D01*
X462500Y210867D01*
X462250Y210908D01*
X461958Y210825D01*
X461750Y210533D01*
X461667Y210242D01*
Y209867D01*
G01Y210242D02*
X461542Y210492D01*
X461333Y210700D01*
X461083Y210783D01*
X460833Y210700D01*
X460625Y210492D01*
X460500Y210117D01*
X460542Y209742D01*
X460708Y209367D01*
G01X461958Y212258D02*
X461667Y212550D01*
X461500Y212800D01*
X461417Y213133D01*
X461500Y213425D01*
X461667Y213633D01*
X461917Y213800D01*
X462208Y213842D01*
X462458Y213800D01*
X462708Y213633D01*
X462917Y213383D01*
X463000Y213092D01*
X462917Y212758D01*
X462667Y212467D01*
X462292Y212300D01*
X461875Y212258D01*
X461333Y212342D01*
X461042Y212467D01*
X460750Y212675D01*
X460542Y212967D01*
X460500Y213258D01*
X460583Y213550D01*
X460792Y213758D01*
G01X463000Y216150D02*
X460500D01*
X461000Y215650D01*
G01X463000D02*
Y216650D01*
G01X455800Y183500D02*
Y177300D01*
X468200D01*
Y183500D01*
G01Y189500D02*
Y195700D01*
X455800D01*
Y189500D01*
G01X447208Y207767D02*
X447083Y207517D01*
X447000Y207225D01*
Y206892D01*
X447125Y206517D01*
X447333Y206225D01*
X447583Y206017D01*
X448000Y205850D01*
X448375Y205808D01*
X448750Y205892D01*
X449000Y206017D01*
X449250Y206267D01*
X449417Y206558D01*
X449500Y206850D01*
Y207142D01*
X449417Y207433D01*
X449292Y207683D01*
X449125Y207892D01*
G01X449000Y209033D02*
X449292Y209283D01*
X449458Y209617D01*
X449500Y209992D01*
X449458Y210325D01*
X449250Y210658D01*
X449000Y210867D01*
X448750Y210908D01*
X448458Y210825D01*
X448250Y210533D01*
X448167Y210242D01*
Y209867D01*
G01Y210242D02*
X448042Y210492D01*
X447833Y210700D01*
X447583Y210783D01*
X447333Y210700D01*
X447125Y210492D01*
X447000Y210117D01*
X447042Y209742D01*
X447208Y209367D01*
G01X448458Y212258D02*
X448167Y212550D01*
X448000Y212800D01*
X447917Y213133D01*
X448000Y213425D01*
X448167Y213633D01*
X448417Y213800D01*
X448708Y213842D01*
X448958Y213800D01*
X449208Y213633D01*
X449417Y213383D01*
X449500Y213092D01*
X449417Y212758D01*
X449167Y212467D01*
X448792Y212300D01*
X448375Y212258D01*
X447833Y212342D01*
X447542Y212467D01*
X447250Y212675D01*
X447042Y212967D01*
X447000Y213258D01*
X447083Y213550D01*
X447292Y213758D01*
G01X447417Y215358D02*
X447167Y215608D01*
X447042Y215900D01*
X447000Y216233D01*
X447083Y216650D01*
X447292Y216942D01*
X447542Y217025D01*
X447792Y216983D01*
X448000Y216817D01*
X448417Y215983D01*
X448708Y215608D01*
X449125Y215358D01*
X449500Y215275D01*
Y217025D01*
G01X442300Y183500D02*
Y177300D01*
X454700D01*
Y183500D01*
G01Y189500D02*
Y195700D01*
X442300D01*
Y189500D01*
G01X432208Y207767D02*
X432083Y207517D01*
X432000Y207225D01*
Y206892D01*
X432125Y206517D01*
X432333Y206225D01*
X432583Y206017D01*
X433000Y205850D01*
X433375Y205808D01*
X433750Y205892D01*
X434000Y206017D01*
X434250Y206267D01*
X434417Y206558D01*
X434500Y206850D01*
Y207142D01*
X434417Y207433D01*
X434292Y207683D01*
X434125Y207892D01*
G01X434000Y209033D02*
X434292Y209283D01*
X434458Y209617D01*
X434500Y209992D01*
X434458Y210325D01*
X434250Y210658D01*
X434000Y210867D01*
X433750Y210908D01*
X433458Y210825D01*
X433250Y210533D01*
X433167Y210242D01*
Y209867D01*
G01Y210242D02*
X433042Y210492D01*
X432833Y210700D01*
X432583Y210783D01*
X432333Y210700D01*
X432125Y210492D01*
X432000Y210117D01*
X432042Y209742D01*
X432208Y209367D01*
G01X433458Y212258D02*
X433167Y212550D01*
X433000Y212800D01*
X432917Y213133D01*
X433000Y213425D01*
X433167Y213633D01*
X433417Y213800D01*
X433708Y213842D01*
X433958Y213800D01*
X434208Y213633D01*
X434417Y213383D01*
X434500Y213092D01*
X434417Y212758D01*
X434167Y212467D01*
X433792Y212300D01*
X433375Y212258D01*
X432833Y212342D01*
X432542Y212467D01*
X432250Y212675D01*
X432042Y212967D01*
X432000Y213258D01*
X432083Y213550D01*
X432292Y213758D01*
G01X434000Y215233D02*
X434292Y215483D01*
X434458Y215817D01*
X434500Y216192D01*
X434458Y216525D01*
X434250Y216858D01*
X434000Y217067D01*
X433750Y217108D01*
X433458Y217025D01*
X433250Y216733D01*
X433167Y216442D01*
Y216067D01*
G01Y216442D02*
X433042Y216692D01*
X432833Y216900D01*
X432583Y216983D01*
X432333Y216900D01*
X432125Y216692D01*
X432000Y216317D01*
X432042Y215942D01*
X432208Y215567D01*
G01X428800Y183500D02*
Y177300D01*
X441200D01*
Y183500D01*
G01Y189500D02*
Y195700D01*
X428800D01*
Y189500D01*
G01X422708Y207267D02*
X422583Y207017D01*
X422500Y206725D01*
Y206392D01*
X422625Y206017D01*
X422833Y205725D01*
X423083Y205517D01*
X423500Y205350D01*
X423875Y205308D01*
X424250Y205392D01*
X424500Y205517D01*
X424750Y205767D01*
X424917Y206058D01*
X425000Y206350D01*
Y206642D01*
X424917Y206933D01*
X424792Y207183D01*
X424625Y207392D01*
G01X424500Y208533D02*
X424792Y208783D01*
X424958Y209117D01*
X425000Y209492D01*
X424958Y209825D01*
X424750Y210158D01*
X424500Y210367D01*
X424250Y210408D01*
X423958Y210325D01*
X423750Y210033D01*
X423667Y209742D01*
Y209367D01*
G01Y209742D02*
X423542Y209992D01*
X423333Y210200D01*
X423083Y210283D01*
X422833Y210200D01*
X422625Y209992D01*
X422500Y209617D01*
X422542Y209242D01*
X422708Y208867D01*
G01X423958Y211758D02*
X423667Y212050D01*
X423500Y212300D01*
X423417Y212633D01*
X423500Y212925D01*
X423667Y213133D01*
X423917Y213300D01*
X424208Y213342D01*
X424458Y213300D01*
X424708Y213133D01*
X424917Y212883D01*
X425000Y212592D01*
X424917Y212258D01*
X424667Y211967D01*
X424292Y211800D01*
X423875Y211758D01*
X423333Y211842D01*
X423042Y211967D01*
X422750Y212175D01*
X422542Y212467D01*
X422500Y212758D01*
X422583Y213050D01*
X422792Y213258D01*
G01X425000Y216150D02*
X422500D01*
X424292Y214608D01*
Y216692D01*
G01X415300Y183500D02*
Y177300D01*
X427700D01*
Y183500D01*
G01Y189500D02*
Y195700D01*
X415300D01*
Y189500D01*
G01X496075Y45000D02*
Y47500D01*
G01X497825D02*
Y45000D01*
G01Y46250D02*
X496075D01*
G01X500550Y45000D02*
Y47500D01*
X499008Y45708D01*
X501092D01*
G01X508900Y217500D02*
Y215000D01*
G01X507942Y217500D02*
X509858D01*
G01X512917Y217292D02*
X512667Y217417D01*
X512375Y217500D01*
X512042D01*
X511667Y217375D01*
X511375Y217167D01*
X511167Y216917D01*
X511000Y216500D01*
X510958Y216125D01*
X511042Y215750D01*
X511167Y215500D01*
X511417Y215250D01*
X511708Y215083D01*
X512000Y215000D01*
X512292D01*
X512583Y215083D01*
X512833Y215208D01*
X513042Y215375D01*
G01X514183D02*
X514433Y215167D01*
X514725Y215042D01*
X515100Y215000D01*
X515475Y215083D01*
X515767Y215250D01*
X515975Y215542D01*
X516017Y215875D01*
X515933Y216208D01*
X515725Y216417D01*
X515433Y216583D01*
X515142Y216625D01*
X514850Y216583D01*
X514475Y216417D01*
X514600Y217500D01*
X515725D01*
G01X503989Y166562D02*
X521989D01*
G01X503989Y177762D02*
Y166562D01*
G01Y204962D02*
X521989D01*
G01X503989Y193762D02*
Y204962D01*
G01X483900Y217500D02*
Y215000D01*
G01X482942Y217500D02*
X484858D01*
G01X487917Y217292D02*
X487667Y217417D01*
X487375Y217500D01*
X487042D01*
X486667Y217375D01*
X486375Y217167D01*
X486167Y216917D01*
X486000Y216500D01*
X485958Y216125D01*
X486042Y215750D01*
X486167Y215500D01*
X486417Y215250D01*
X486708Y215083D01*
X487000Y215000D01*
X487292D01*
X487583Y215083D01*
X487833Y215208D01*
X488042Y215375D01*
G01X489183Y215500D02*
X489433Y215208D01*
X489767Y215042D01*
X490142Y215000D01*
X490475Y215042D01*
X490808Y215250D01*
X491017Y215500D01*
X491058Y215750D01*
X490975Y216042D01*
X490683Y216250D01*
X490392Y216333D01*
X490017D01*
G01X490392D02*
X490642Y216458D01*
X490850Y216667D01*
X490933Y216917D01*
X490850Y217167D01*
X490642Y217375D01*
X490267Y217500D01*
X489892Y217458D01*
X489517Y217292D01*
G01X496625Y166486D02*
Y177686D01*
G01X478625Y166486D02*
X496625D01*
G01X478625Y177686D02*
Y166486D01*
G01X496625Y204886D02*
Y193686D01*
G01X478625Y204886D02*
X496625D01*
G01X478625Y193686D02*
Y204886D01*
G01X471208Y207767D02*
X471083Y207517D01*
X471000Y207225D01*
Y206892D01*
X471125Y206517D01*
X471333Y206225D01*
X471583Y206017D01*
X472000Y205850D01*
X472375Y205808D01*
X472750Y205892D01*
X473000Y206017D01*
X473250Y206267D01*
X473417Y206558D01*
X473500Y206850D01*
Y207142D01*
X473417Y207433D01*
X473292Y207683D01*
X473125Y207892D01*
G01X473000Y209033D02*
X473292Y209283D01*
X473458Y209617D01*
X473500Y209992D01*
X473458Y210325D01*
X473250Y210658D01*
X473000Y210867D01*
X472750Y210908D01*
X472458Y210825D01*
X472250Y210533D01*
X472167Y210242D01*
Y209867D01*
G01Y210242D02*
X472042Y210492D01*
X471833Y210700D01*
X471583Y210783D01*
X471333Y210700D01*
X471125Y210492D01*
X471000Y210117D01*
X471042Y209742D01*
X471208Y209367D01*
G01X473125Y212133D02*
X473333Y212383D01*
X473458Y212675D01*
X473500Y213050D01*
X473417Y213425D01*
X473250Y213717D01*
X472958Y213925D01*
X472625Y213967D01*
X472292Y213883D01*
X472083Y213675D01*
X471917Y213383D01*
X471875Y213092D01*
X471917Y212800D01*
X472083Y212425D01*
X471000Y212550D01*
Y213675D01*
G01X473125Y215233D02*
X473333Y215483D01*
X473458Y215775D01*
X473500Y216150D01*
X473417Y216525D01*
X473250Y216817D01*
X472958Y217025D01*
X472625Y217067D01*
X472292Y216983D01*
X472083Y216775D01*
X471917Y216483D01*
X471875Y216192D01*
X471917Y215900D01*
X472083Y215525D01*
X471000Y215650D01*
Y216775D01*
G01X519517Y267500D02*
Y270000D01*
X520558D01*
X520892Y269875D01*
X521100Y269708D01*
X521183Y269375D01*
X521100Y269042D01*
X520850Y268833D01*
X520558Y268708D01*
X519517D01*
G01X520558D02*
X521183Y267500D01*
G01X522533Y268000D02*
X522783Y267708D01*
X523117Y267542D01*
X523492Y267500D01*
X523825Y267542D01*
X524158Y267750D01*
X524367Y268000D01*
X524408Y268250D01*
X524325Y268542D01*
X524033Y268750D01*
X523742Y268833D01*
X523367D01*
G01X523742D02*
X523992Y268958D01*
X524200Y269167D01*
X524283Y269417D01*
X524200Y269667D01*
X523992Y269875D01*
X523617Y270000D01*
X523242Y269958D01*
X522867Y269792D01*
G01X526550Y267500D02*
X526842Y267542D01*
X527175Y267667D01*
X527383Y267875D01*
X527467Y268167D01*
X527383Y268458D01*
X527133Y268708D01*
X526758Y268833D01*
X526342D01*
X526092Y268917D01*
X525883Y269125D01*
X525800Y269417D01*
X525925Y269708D01*
X526217Y269917D01*
X526550Y270000D01*
X526883Y269917D01*
X527175Y269708D01*
X527300Y269417D01*
X527217Y269125D01*
X527008Y268917D01*
X526758Y268833D01*
X526342D01*
X525967Y268708D01*
X525717Y268458D01*
X525633Y268167D01*
X525717Y267875D01*
X525925Y267667D01*
X526258Y267542D01*
X526550Y267500D01*
G01X528858Y268542D02*
X529150Y268833D01*
X529400Y269000D01*
X529733Y269083D01*
X530025Y269000D01*
X530233Y268833D01*
X530400Y268583D01*
X530442Y268292D01*
X530400Y268042D01*
X530233Y267792D01*
X529983Y267583D01*
X529692Y267500D01*
X529358Y267583D01*
X529067Y267833D01*
X528900Y268208D01*
X528858Y268625D01*
X528942Y269167D01*
X529067Y269458D01*
X529275Y269750D01*
X529567Y269958D01*
X529858Y270000D01*
X530150Y269917D01*
X530358Y269708D01*
G01X519517Y263000D02*
Y265500D01*
X520558D01*
X520892Y265375D01*
X521100Y265208D01*
X521183Y264875D01*
X521100Y264542D01*
X520850Y264333D01*
X520558Y264208D01*
X519517D01*
G01X520558D02*
X521183Y263000D01*
G01X522533Y263500D02*
X522783Y263208D01*
X523117Y263042D01*
X523492Y263000D01*
X523825Y263042D01*
X524158Y263250D01*
X524367Y263500D01*
X524408Y263750D01*
X524325Y264042D01*
X524033Y264250D01*
X523742Y264333D01*
X523367D01*
G01X523742D02*
X523992Y264458D01*
X524200Y264667D01*
X524283Y264917D01*
X524200Y265167D01*
X523992Y265375D01*
X523617Y265500D01*
X523242Y265458D01*
X522867Y265292D01*
G01X526550Y263000D02*
X526842Y263042D01*
X527175Y263167D01*
X527383Y263375D01*
X527467Y263667D01*
X527383Y263958D01*
X527133Y264208D01*
X526758Y264333D01*
X526342D01*
X526092Y264417D01*
X525883Y264625D01*
X525800Y264917D01*
X525925Y265208D01*
X526217Y265417D01*
X526550Y265500D01*
X526883Y265417D01*
X527175Y265208D01*
X527300Y264917D01*
X527217Y264625D01*
X527008Y264417D01*
X526758Y264333D01*
X526342D01*
X525967Y264208D01*
X525717Y263958D01*
X525633Y263667D01*
X525717Y263375D01*
X525925Y263167D01*
X526258Y263042D01*
X526550Y263000D01*
G01X529567D02*
X529650Y263542D01*
X529775Y264000D01*
X529942Y264417D01*
X530150Y264875D01*
X530483Y265500D01*
X528817D01*
G01X516610Y233674D02*
Y238674D01*
X518610D01*
X519277Y238424D01*
X519777Y237841D01*
X519944Y237174D01*
X519777Y236507D01*
X519360Y236007D01*
X518610Y235757D01*
X516610D01*
G01X522960Y235341D02*
X524960D01*
G01X523877Y236424D02*
Y234257D01*
G01X527727Y234341D02*
X528394Y233924D01*
X529144Y233674D01*
X529810D01*
X530477Y233924D01*
X530977Y234341D01*
X531227Y234924D01*
X531060Y235507D01*
X530644Y236007D01*
X529894Y236341D01*
X528894Y236507D01*
X528310Y236841D01*
X528060Y237424D01*
X528227Y238007D01*
X528644Y238424D01*
X529227Y238674D01*
X529810D01*
X530394Y238507D01*
X530894Y238091D01*
G01X542510Y238257D02*
X542010Y238507D01*
X541427Y238674D01*
X540760D01*
X540010Y238424D01*
X539427Y238007D01*
X539010Y237507D01*
X538677Y236674D01*
X538594Y235924D01*
X538760Y235174D01*
X539010Y234674D01*
X539510Y234174D01*
X540094Y233841D01*
X540677Y233674D01*
X541260D01*
X541844Y233841D01*
X542344Y234091D01*
X542760Y234424D01*
G01X546277Y233674D02*
X545610Y233757D01*
X545027Y234091D01*
X544527Y234591D01*
X544194Y235174D01*
X544027Y235841D01*
Y236507D01*
X544194Y237174D01*
X544527Y237757D01*
X545027Y238257D01*
X545610Y238591D01*
X546277Y238674D01*
X546944Y238591D01*
X547527Y238257D01*
X548027Y237757D01*
X548360Y237174D01*
X548527Y236507D01*
Y235841D01*
X548360Y235174D01*
X548027Y234591D01*
X547527Y234091D01*
X546944Y233757D01*
X546277Y233674D01*
G01X549960D02*
Y238674D01*
X553794Y233674D01*
Y238674D01*
G01X555560Y233674D02*
Y238674D01*
X559394Y233674D01*
Y238674D01*
G01X498517Y321500D02*
Y324000D01*
X499558D01*
X499892Y323875D01*
X500100Y323708D01*
X500183Y323375D01*
X500100Y323042D01*
X499850Y322833D01*
X499558Y322708D01*
X498517D01*
G01X499558D02*
X500183Y321500D01*
G01X502950D02*
Y324000D01*
X501408Y322208D01*
X503492D01*
G01X505550Y321500D02*
X505842Y321542D01*
X506175Y321667D01*
X506383Y321875D01*
X506467Y322167D01*
X506383Y322458D01*
X506133Y322708D01*
X505758Y322833D01*
X505342D01*
X505092Y322917D01*
X504883Y323125D01*
X504800Y323417D01*
X504925Y323708D01*
X505217Y323917D01*
X505550Y324000D01*
X505883Y323917D01*
X506175Y323708D01*
X506300Y323417D01*
X506217Y323125D01*
X506008Y322917D01*
X505758Y322833D01*
X505342D01*
X504967Y322708D01*
X504717Y322458D01*
X504633Y322167D01*
X504717Y321875D01*
X504925Y321667D01*
X505258Y321542D01*
X505550Y321500D01*
G01X507858Y323583D02*
X508108Y323833D01*
X508400Y323958D01*
X508733Y324000D01*
X509150Y323917D01*
X509442Y323708D01*
X509525Y323458D01*
X509483Y323208D01*
X509317Y323000D01*
X508483Y322583D01*
X508108Y322292D01*
X507858Y321875D01*
X507775Y321500D01*
X509525D01*
G01X498517Y325500D02*
Y328000D01*
X499558D01*
X499892Y327875D01*
X500100Y327708D01*
X500183Y327375D01*
X500100Y327042D01*
X499850Y326833D01*
X499558Y326708D01*
X498517D01*
G01X499558D02*
X500183Y325500D01*
G01X501533Y326000D02*
X501783Y325708D01*
X502117Y325542D01*
X502492Y325500D01*
X502825Y325542D01*
X503158Y325750D01*
X503367Y326000D01*
X503408Y326250D01*
X503325Y326542D01*
X503033Y326750D01*
X502742Y326833D01*
X502367D01*
G01X502742D02*
X502992Y326958D01*
X503200Y327167D01*
X503283Y327417D01*
X503200Y327667D01*
X502992Y327875D01*
X502617Y328000D01*
X502242Y327958D01*
X501867Y327792D01*
G01X505467Y325500D02*
X505550Y326042D01*
X505675Y326500D01*
X505842Y326917D01*
X506050Y327375D01*
X506383Y328000D01*
X504717D01*
G01X507858Y326542D02*
X508150Y326833D01*
X508400Y327000D01*
X508733Y327083D01*
X509025Y327000D01*
X509233Y326833D01*
X509400Y326583D01*
X509442Y326292D01*
X509400Y326042D01*
X509233Y325792D01*
X508983Y325583D01*
X508692Y325500D01*
X508358Y325583D01*
X508067Y325833D01*
X507900Y326208D01*
X507858Y326625D01*
X507942Y327167D01*
X508067Y327458D01*
X508275Y327750D01*
X508567Y327958D01*
X508858Y328000D01*
X509150Y327917D01*
X509358Y327708D01*
G01X517500Y308400D02*
X517458Y308067D01*
X517292Y307775D01*
X517042Y307525D01*
X516750Y307358D01*
X516417Y307275D01*
X516083D01*
X515750Y307358D01*
X515458Y307525D01*
X515208Y307775D01*
X515042Y308067D01*
X515000Y308400D01*
X515042Y308733D01*
X515208Y309025D01*
X515458Y309275D01*
X515750Y309442D01*
X516083Y309525D01*
X516417D01*
X516750Y309442D01*
X517042Y309275D01*
X517292Y309025D01*
X517458Y308733D01*
X517500Y308400D01*
G01X516833Y308733D02*
X517500Y309233D01*
G01X517000Y310583D02*
X517292Y310833D01*
X517458Y311167D01*
X517500Y311542D01*
X517458Y311875D01*
X517250Y312208D01*
X517000Y312417D01*
X516750Y312458D01*
X516458Y312375D01*
X516250Y312083D01*
X516167Y311792D01*
Y311417D01*
G01Y311792D02*
X516042Y312042D01*
X515833Y312250D01*
X515583Y312333D01*
X515333Y312250D01*
X515125Y312042D01*
X515000Y311667D01*
X515042Y311292D01*
X515208Y310917D01*
G01X517000Y313683D02*
X517292Y313933D01*
X517458Y314267D01*
X517500Y314642D01*
X517458Y314975D01*
X517250Y315308D01*
X517000Y315517D01*
X516750Y315558D01*
X516458Y315475D01*
X516250Y315183D01*
X516167Y314892D01*
Y314517D01*
G01Y314892D02*
X516042Y315142D01*
X515833Y315350D01*
X515583Y315433D01*
X515333Y315350D01*
X515125Y315142D01*
X515000Y314767D01*
X515042Y314392D01*
X515208Y314017D01*
G01X517500Y294900D02*
X517458Y294567D01*
X517292Y294275D01*
X517042Y294025D01*
X516750Y293858D01*
X516417Y293775D01*
X516083D01*
X515750Y293858D01*
X515458Y294025D01*
X515208Y294275D01*
X515042Y294567D01*
X515000Y294900D01*
X515042Y295233D01*
X515208Y295525D01*
X515458Y295775D01*
X515750Y295942D01*
X516083Y296025D01*
X516417D01*
X516750Y295942D01*
X517042Y295775D01*
X517292Y295525D01*
X517458Y295233D01*
X517500Y294900D01*
G01X516833Y295233D02*
X517500Y295733D01*
G01X517000Y297083D02*
X517292Y297333D01*
X517458Y297667D01*
X517500Y298042D01*
X517458Y298375D01*
X517250Y298708D01*
X517000Y298917D01*
X516750Y298958D01*
X516458Y298875D01*
X516250Y298583D01*
X516167Y298292D01*
Y297917D01*
G01Y298292D02*
X516042Y298542D01*
X515833Y298750D01*
X515583Y298833D01*
X515333Y298750D01*
X515125Y298542D01*
X515000Y298167D01*
X515042Y297792D01*
X515208Y297417D01*
G01X517500Y301600D02*
X515000D01*
X516792Y300058D01*
Y302142D01*
G01X520800Y328000D02*
Y324000D01*
X528200D01*
G01Y320000D02*
Y324000D01*
X520800D01*
G01X516075Y456500D02*
Y459000D01*
G01X517825D02*
Y456500D01*
G01Y457750D02*
X516075D01*
G01X520050Y456500D02*
Y459000D01*
X519550Y458500D01*
G01Y456500D02*
X520550D01*
G01X567517Y79000D02*
Y81500D01*
X568558D01*
X568892Y81375D01*
X569100Y81208D01*
X569183Y80875D01*
X569100Y80542D01*
X568850Y80333D01*
X568558Y80208D01*
X567517D01*
G01X568558D02*
X569183Y79000D01*
G01X570533Y79500D02*
X570783Y79208D01*
X571117Y79042D01*
X571492Y79000D01*
X571825Y79042D01*
X572158Y79250D01*
X572367Y79500D01*
X572408Y79750D01*
X572325Y80042D01*
X572033Y80250D01*
X571742Y80333D01*
X571367D01*
G01X571742D02*
X571992Y80458D01*
X572200Y80667D01*
X572283Y80917D01*
X572200Y81167D01*
X571992Y81375D01*
X571617Y81500D01*
X571242Y81458D01*
X570867Y81292D01*
G01X573842Y79292D02*
X574133Y79083D01*
X574467Y79000D01*
X574800Y79083D01*
X575092Y79333D01*
X575300Y79708D01*
X575383Y80083D01*
Y80542D01*
X575300Y80917D01*
X575092Y81250D01*
X574842Y81417D01*
X574550Y81500D01*
X574217Y81417D01*
X573967Y81250D01*
X573800Y81000D01*
X573717Y80667D01*
X573800Y80375D01*
X574008Y80083D01*
X574258Y79917D01*
X574550Y79875D01*
X574883Y79958D01*
X575133Y80167D01*
X575383Y80542D01*
G01X577650Y79000D02*
Y81500D01*
X577150Y81000D01*
G01Y79000D02*
X578150D01*
G01X563517Y70000D02*
Y72500D01*
X564558D01*
X564892Y72375D01*
X565100Y72208D01*
X565183Y71875D01*
X565100Y71542D01*
X564850Y71333D01*
X564558Y71208D01*
X563517D01*
G01X564558D02*
X565183Y70000D01*
G01X566533Y70500D02*
X566783Y70208D01*
X567117Y70042D01*
X567492Y70000D01*
X567825Y70042D01*
X568158Y70250D01*
X568367Y70500D01*
X568408Y70750D01*
X568325Y71042D01*
X568033Y71250D01*
X567742Y71333D01*
X567367D01*
G01X567742D02*
X567992Y71458D01*
X568200Y71667D01*
X568283Y71917D01*
X568200Y72167D01*
X567992Y72375D01*
X567617Y72500D01*
X567242Y72458D01*
X566867Y72292D01*
G01X569842Y70292D02*
X570133Y70083D01*
X570467Y70000D01*
X570800Y70083D01*
X571092Y70333D01*
X571300Y70708D01*
X571383Y71083D01*
Y71542D01*
X571300Y71917D01*
X571092Y72250D01*
X570842Y72417D01*
X570550Y72500D01*
X570217Y72417D01*
X569967Y72250D01*
X569800Y72000D01*
X569717Y71667D01*
X569800Y71375D01*
X570008Y71083D01*
X570258Y70917D01*
X570550Y70875D01*
X570883Y70958D01*
X571133Y71167D01*
X571383Y71542D01*
G01X573650Y72500D02*
X573317Y72417D01*
X573067Y72208D01*
X572900Y71958D01*
X572775Y71625D01*
X572733Y71250D01*
X572775Y70875D01*
X572900Y70542D01*
X573067Y70292D01*
X573317Y70083D01*
X573650Y70000D01*
X573983Y70083D01*
X574233Y70292D01*
X574400Y70542D01*
X574525Y70875D01*
X574567Y71250D01*
X574525Y71625D01*
X574400Y71958D01*
X574233Y72208D01*
X573983Y72417D01*
X573650Y72500D01*
G01X577500Y55000D02*
X576833Y55083D01*
X576250Y55417D01*
X575750Y55917D01*
X575417Y56500D01*
X575250Y57167D01*
Y57833D01*
X575417Y58500D01*
X575750Y59083D01*
X576250Y59583D01*
X576833Y59917D01*
X577500Y60000D01*
X578167Y59917D01*
X578750Y59583D01*
X579250Y59083D01*
X579583Y58500D01*
X579750Y57833D01*
Y57167D01*
X579583Y56500D01*
X579250Y55917D01*
X578750Y55417D01*
X578167Y55083D01*
X577500Y55000D01*
G01X581517D02*
Y60000D01*
X584683D01*
G01X583517Y57583D02*
X581517D01*
G01X587117Y55000D02*
Y60000D01*
X590283D01*
G01X589117Y57583D02*
X587117D01*
G01X583107Y64918D02*
Y68918D01*
X575707D01*
G01X560208Y130565D02*
X560083Y130315D01*
X560000Y130023D01*
Y129690D01*
X560125Y129315D01*
X560333Y129023D01*
X560583Y128815D01*
X561000Y128648D01*
X561375Y128606D01*
X561750Y128690D01*
X562000Y128815D01*
X562250Y129065D01*
X562417Y129356D01*
X562500Y129648D01*
Y129940D01*
X562417Y130231D01*
X562292Y130481D01*
X562125Y130690D01*
G01X562500Y131790D02*
X560000D01*
X562500Y133706D01*
X560000D01*
G01X562500Y136348D02*
X560000D01*
X561792Y134806D01*
Y136890D01*
G01X566809Y120909D02*
Y327909D01*
X620709D01*
Y120909D01*
X566809D01*
G01X535400Y217000D02*
Y214500D01*
G01X534442Y217000D02*
X536358D01*
G01X539417Y216792D02*
X539167Y216917D01*
X538875Y217000D01*
X538542D01*
X538167Y216875D01*
X537875Y216667D01*
X537667Y216417D01*
X537500Y216000D01*
X537458Y215625D01*
X537542Y215250D01*
X537667Y215000D01*
X537917Y214750D01*
X538208Y214583D01*
X538500Y214500D01*
X538792D01*
X539083Y214583D01*
X539333Y214708D01*
X539542Y214875D01*
G01X542100Y214500D02*
Y217000D01*
X540558Y215208D01*
X542642D01*
G01X547135Y166577D02*
Y177777D01*
G01X529135Y166577D02*
X547135D01*
G01X529135Y177777D02*
Y166577D01*
G01X547135Y204977D02*
Y193777D01*
G01X529135Y204977D02*
X547135D01*
G01X529135Y193777D02*
Y204977D01*
G01X521989Y166562D02*
Y177762D01*
G01Y204962D02*
Y193762D01*
G01X541208Y244767D02*
X541083Y244517D01*
X541000Y244225D01*
Y243892D01*
X541125Y243517D01*
X541333Y243225D01*
X541583Y243017D01*
X542000Y242850D01*
X542375Y242808D01*
X542750Y242892D01*
X543000Y243017D01*
X543250Y243267D01*
X543417Y243558D01*
X543500Y243850D01*
Y244142D01*
X543417Y244433D01*
X543292Y244683D01*
X543125Y244892D01*
G01X543000Y246033D02*
X543292Y246283D01*
X543458Y246617D01*
X543500Y246992D01*
X543458Y247325D01*
X543250Y247658D01*
X543000Y247867D01*
X542750Y247908D01*
X542458Y247825D01*
X542250Y247533D01*
X542167Y247242D01*
Y246867D01*
G01Y247242D02*
X542042Y247492D01*
X541833Y247700D01*
X541583Y247783D01*
X541333Y247700D01*
X541125Y247492D01*
X541000Y247117D01*
X541042Y246742D01*
X541208Y246367D01*
G01X543125Y249133D02*
X543333Y249383D01*
X543458Y249675D01*
X543500Y250050D01*
X543417Y250425D01*
X543250Y250717D01*
X542958Y250925D01*
X542625Y250967D01*
X542292Y250883D01*
X542083Y250675D01*
X541917Y250383D01*
X541875Y250092D01*
X541917Y249800D01*
X542083Y249425D01*
X541000Y249550D01*
Y250675D01*
G01X543208Y252442D02*
X543417Y252733D01*
X543500Y253067D01*
X543417Y253400D01*
X543167Y253692D01*
X542792Y253900D01*
X542417Y253983D01*
X541958D01*
X541583Y253900D01*
X541250Y253692D01*
X541083Y253442D01*
X541000Y253150D01*
X541083Y252817D01*
X541250Y252567D01*
X541500Y252400D01*
X541833Y252317D01*
X542125Y252400D01*
X542417Y252608D01*
X542583Y252858D01*
X542625Y253150D01*
X542542Y253483D01*
X542333Y253733D01*
X541958Y253983D01*
G01X532333Y265971D02*
Y261971D01*
X539733D01*
G01X532333Y270971D02*
Y266971D01*
X539733D01*
G01X559000Y320417D02*
X556500D01*
Y321458D01*
X556625Y321792D01*
X556792Y322000D01*
X557125Y322083D01*
X557458Y322000D01*
X557667Y321750D01*
X557792Y321458D01*
Y320417D01*
G01Y321458D02*
X559000Y322083D01*
G01X558500Y323433D02*
X558792Y323683D01*
X558958Y324017D01*
X559000Y324392D01*
X558958Y324725D01*
X558750Y325058D01*
X558500Y325267D01*
X558250Y325308D01*
X557958Y325225D01*
X557750Y324933D01*
X557667Y324642D01*
Y324267D01*
G01Y324642D02*
X557542Y324892D01*
X557333Y325100D01*
X557083Y325183D01*
X556833Y325100D01*
X556625Y324892D01*
X556500Y324517D01*
X556542Y324142D01*
X556708Y323767D01*
G01X559000Y327367D02*
X558458Y327450D01*
X558000Y327575D01*
X557583Y327742D01*
X557125Y327950D01*
X556500Y328283D01*
Y326617D01*
G01X559000Y330550D02*
X558958Y330842D01*
X558833Y331175D01*
X558625Y331383D01*
X558333Y331467D01*
X558042Y331383D01*
X557792Y331133D01*
X557667Y330758D01*
Y330342D01*
X557583Y330092D01*
X557375Y329883D01*
X557083Y329800D01*
X556792Y329925D01*
X556583Y330217D01*
X556500Y330550D01*
X556583Y330883D01*
X556792Y331175D01*
X557083Y331300D01*
X557375Y331217D01*
X557583Y331008D01*
X557667Y330758D01*
Y330342D01*
X557792Y329967D01*
X558042Y329717D01*
X558333Y329633D01*
X558625Y329717D01*
X558833Y329925D01*
X558958Y330258D01*
X559000Y330550D01*
G01X541708Y280267D02*
X541583Y280017D01*
X541500Y279725D01*
Y279392D01*
X541625Y279017D01*
X541833Y278725D01*
X542083Y278517D01*
X542500Y278350D01*
X542875Y278308D01*
X543250Y278392D01*
X543500Y278517D01*
X543750Y278767D01*
X543917Y279058D01*
X544000Y279350D01*
Y279642D01*
X543917Y279933D01*
X543792Y280183D01*
X543625Y280392D01*
G01X543500Y281533D02*
X543792Y281783D01*
X543958Y282117D01*
X544000Y282492D01*
X543958Y282825D01*
X543750Y283158D01*
X543500Y283367D01*
X543250Y283408D01*
X542958Y283325D01*
X542750Y283033D01*
X542667Y282742D01*
Y282367D01*
G01Y282742D02*
X542542Y282992D01*
X542333Y283200D01*
X542083Y283283D01*
X541833Y283200D01*
X541625Y282992D01*
X541500Y282617D01*
X541542Y282242D01*
X541708Y281867D01*
G01X542958Y284758D02*
X542667Y285050D01*
X542500Y285300D01*
X542417Y285633D01*
X542500Y285925D01*
X542667Y286133D01*
X542917Y286300D01*
X543208Y286342D01*
X543458Y286300D01*
X543708Y286133D01*
X543917Y285883D01*
X544000Y285592D01*
X543917Y285258D01*
X543667Y284967D01*
X543292Y284800D01*
X542875Y284758D01*
X542333Y284842D01*
X542042Y284967D01*
X541750Y285175D01*
X541542Y285467D01*
X541500Y285758D01*
X541583Y286050D01*
X541792Y286258D01*
G01X541500Y288650D02*
X541583Y288317D01*
X541792Y288067D01*
X542042Y287900D01*
X542375Y287775D01*
X542750Y287733D01*
X543125Y287775D01*
X543458Y287900D01*
X543708Y288067D01*
X543917Y288317D01*
X544000Y288650D01*
X543917Y288983D01*
X543708Y289233D01*
X543458Y289400D01*
X543125Y289525D01*
X542750Y289567D01*
X542375Y289525D01*
X542042Y289400D01*
X541792Y289233D01*
X541583Y288983D01*
X541500Y288650D01*
G01X544000Y293517D02*
X541500D01*
Y294558D01*
X541625Y294892D01*
X541792Y295100D01*
X542125Y295183D01*
X542458Y295100D01*
X542667Y294850D01*
X542792Y294558D01*
Y293517D01*
G01Y294558D02*
X544000Y295183D01*
G01X543500Y296533D02*
X543792Y296783D01*
X543958Y297117D01*
X544000Y297492D01*
X543958Y297825D01*
X543750Y298158D01*
X543500Y298367D01*
X543250Y298408D01*
X542958Y298325D01*
X542750Y298033D01*
X542667Y297742D01*
Y297367D01*
G01Y297742D02*
X542542Y297992D01*
X542333Y298200D01*
X542083Y298283D01*
X541833Y298200D01*
X541625Y297992D01*
X541500Y297617D01*
X541542Y297242D01*
X541708Y296867D01*
G01X544000Y300467D02*
X543458Y300550D01*
X543000Y300675D01*
X542583Y300842D01*
X542125Y301050D01*
X541500Y301383D01*
Y299717D01*
G01X543708Y302942D02*
X543917Y303233D01*
X544000Y303567D01*
X543917Y303900D01*
X543667Y304192D01*
X543292Y304400D01*
X542917Y304483D01*
X542458D01*
X542083Y304400D01*
X541750Y304192D01*
X541583Y303942D01*
X541500Y303650D01*
X541583Y303317D01*
X541750Y303067D01*
X542000Y302900D01*
X542333Y302817D01*
X542625Y302900D01*
X542917Y303108D01*
X543083Y303358D01*
X543125Y303650D01*
X543042Y303983D01*
X542833Y304233D01*
X542458Y304483D01*
G01X540000Y298700D02*
X536000D01*
Y291300D01*
G01X535511Y290007D02*
Y304007D01*
G01X522511Y290007D02*
X535511D01*
G01X522511Y304007D02*
Y290007D01*
G01X535511Y304007D02*
X522511D01*
G01X535536Y305102D02*
Y319102D01*
G01X522536Y305102D02*
X535536D01*
G01X522536Y319102D02*
Y305102D01*
G01X535536Y319102D02*
X522536D01*
G01X528236Y328402D02*
Y324402D01*
X535636D01*
G01X528136Y332602D02*
Y328602D01*
X535536D01*
G01X528236Y324102D02*
Y320102D01*
X535636D01*
G01X553998Y332836D02*
Y327636D01*
G01X546998Y332836D02*
Y325036D01*
G01X553998Y319436D02*
Y328136D01*
G01X546998Y319436D02*
X553998D01*
G01X546998Y325836D02*
Y319436D01*
G01X531517Y349500D02*
Y352000D01*
X532558D01*
X532892Y351875D01*
X533100Y351708D01*
X533183Y351375D01*
X533100Y351042D01*
X532850Y350833D01*
X532558Y350708D01*
X531517D01*
G01X532558D02*
X533183Y349500D01*
G01X534533Y350000D02*
X534783Y349708D01*
X535117Y349542D01*
X535492Y349500D01*
X535825Y349542D01*
X536158Y349750D01*
X536367Y350000D01*
X536408Y350250D01*
X536325Y350542D01*
X536033Y350750D01*
X535742Y350833D01*
X535367D01*
G01X535742D02*
X535992Y350958D01*
X536200Y351167D01*
X536283Y351417D01*
X536200Y351667D01*
X535992Y351875D01*
X535617Y352000D01*
X535242Y351958D01*
X534867Y351792D01*
G01X537758Y350542D02*
X538050Y350833D01*
X538300Y351000D01*
X538633Y351083D01*
X538925Y351000D01*
X539133Y350833D01*
X539300Y350583D01*
X539342Y350292D01*
X539300Y350042D01*
X539133Y349792D01*
X538883Y349583D01*
X538592Y349500D01*
X538258Y349583D01*
X537967Y349833D01*
X537800Y350208D01*
X537758Y350625D01*
X537842Y351167D01*
X537967Y351458D01*
X538175Y351750D01*
X538467Y351958D01*
X538758Y352000D01*
X539050Y351917D01*
X539258Y351708D01*
G01X540858Y350542D02*
X541150Y350833D01*
X541400Y351000D01*
X541733Y351083D01*
X542025Y351000D01*
X542233Y350833D01*
X542400Y350583D01*
X542442Y350292D01*
X542400Y350042D01*
X542233Y349792D01*
X541983Y349583D01*
X541692Y349500D01*
X541358Y349583D01*
X541067Y349833D01*
X540900Y350208D01*
X540858Y350625D01*
X540942Y351167D01*
X541067Y351458D01*
X541275Y351750D01*
X541567Y351958D01*
X541858Y352000D01*
X542150Y351917D01*
X542358Y351708D01*
G01X531517Y345500D02*
Y348000D01*
X532558D01*
X532892Y347875D01*
X533100Y347708D01*
X533183Y347375D01*
X533100Y347042D01*
X532850Y346833D01*
X532558Y346708D01*
X531517D01*
G01X532558D02*
X533183Y345500D01*
G01X534533Y346000D02*
X534783Y345708D01*
X535117Y345542D01*
X535492Y345500D01*
X535825Y345542D01*
X536158Y345750D01*
X536367Y346000D01*
X536408Y346250D01*
X536325Y346542D01*
X536033Y346750D01*
X535742Y346833D01*
X535367D01*
G01X535742D02*
X535992Y346958D01*
X536200Y347167D01*
X536283Y347417D01*
X536200Y347667D01*
X535992Y347875D01*
X535617Y348000D01*
X535242Y347958D01*
X534867Y347792D01*
G01X537758Y346542D02*
X538050Y346833D01*
X538300Y347000D01*
X538633Y347083D01*
X538925Y347000D01*
X539133Y346833D01*
X539300Y346583D01*
X539342Y346292D01*
X539300Y346042D01*
X539133Y345792D01*
X538883Y345583D01*
X538592Y345500D01*
X538258Y345583D01*
X537967Y345833D01*
X537800Y346208D01*
X537758Y346625D01*
X537842Y347167D01*
X537967Y347458D01*
X538175Y347750D01*
X538467Y347958D01*
X538758Y348000D01*
X539050Y347917D01*
X539258Y347708D01*
G01X540733Y345875D02*
X540983Y345667D01*
X541275Y345542D01*
X541650Y345500D01*
X542025Y345583D01*
X542317Y345750D01*
X542525Y346042D01*
X542567Y346375D01*
X542483Y346708D01*
X542275Y346917D01*
X541983Y347083D01*
X541692Y347125D01*
X541400Y347083D01*
X541025Y346917D01*
X541150Y348000D01*
X542275D01*
G01X531517Y341500D02*
Y344000D01*
X532558D01*
X532892Y343875D01*
X533100Y343708D01*
X533183Y343375D01*
X533100Y343042D01*
X532850Y342833D01*
X532558Y342708D01*
X531517D01*
G01X532558D02*
X533183Y341500D01*
G01X534533Y342000D02*
X534783Y341708D01*
X535117Y341542D01*
X535492Y341500D01*
X535825Y341542D01*
X536158Y341750D01*
X536367Y342000D01*
X536408Y342250D01*
X536325Y342542D01*
X536033Y342750D01*
X535742Y342833D01*
X535367D01*
G01X535742D02*
X535992Y342958D01*
X536200Y343167D01*
X536283Y343417D01*
X536200Y343667D01*
X535992Y343875D01*
X535617Y344000D01*
X535242Y343958D01*
X534867Y343792D01*
G01X538467Y341500D02*
X538550Y342042D01*
X538675Y342500D01*
X538842Y342917D01*
X539050Y343375D01*
X539383Y344000D01*
X537717D01*
G01X542150Y341500D02*
Y344000D01*
X540608Y342208D01*
X542692D01*
G01X531517Y338000D02*
Y340500D01*
X532558D01*
X532892Y340375D01*
X533100Y340208D01*
X533183Y339875D01*
X533100Y339542D01*
X532850Y339333D01*
X532558Y339208D01*
X531517D01*
G01X532558D02*
X533183Y338000D01*
G01X534533Y338500D02*
X534783Y338208D01*
X535117Y338042D01*
X535492Y338000D01*
X535825Y338042D01*
X536158Y338250D01*
X536367Y338500D01*
X536408Y338750D01*
X536325Y339042D01*
X536033Y339250D01*
X535742Y339333D01*
X535367D01*
G01X535742D02*
X535992Y339458D01*
X536200Y339667D01*
X536283Y339917D01*
X536200Y340167D01*
X535992Y340375D01*
X535617Y340500D01*
X535242Y340458D01*
X534867Y340292D01*
G01X538467Y338000D02*
X538550Y338542D01*
X538675Y339000D01*
X538842Y339417D01*
X539050Y339875D01*
X539383Y340500D01*
X537717D01*
G01X540733Y338375D02*
X540983Y338167D01*
X541275Y338042D01*
X541650Y338000D01*
X542025Y338083D01*
X542317Y338250D01*
X542525Y338542D01*
X542567Y338875D01*
X542483Y339208D01*
X542275Y339417D01*
X541983Y339583D01*
X541692Y339625D01*
X541400Y339583D01*
X541025Y339417D01*
X541150Y340500D01*
X542275D01*
G01X535536Y332902D02*
Y336902D01*
X528136D01*
G01X553998Y332836D02*
X546998D01*
G01X582000Y91000D02*
X581333Y91083D01*
X580750Y91417D01*
X580250Y91917D01*
X579917Y92500D01*
X579750Y93167D01*
Y93833D01*
X579917Y94500D01*
X580250Y95083D01*
X580750Y95583D01*
X581333Y95917D01*
X582000Y96000D01*
X582667Y95917D01*
X583250Y95583D01*
X583750Y95083D01*
X584083Y94500D01*
X584250Y93833D01*
Y93167D01*
X584083Y92500D01*
X583750Y91917D01*
X583250Y91417D01*
X582667Y91083D01*
X582000Y91000D01*
G01X585683D02*
Y96000D01*
X589517Y91000D01*
Y96000D01*
G01X596525Y97833D02*
X596858Y97625D01*
X597233Y97500D01*
X597567D01*
X597900Y97625D01*
X598150Y97833D01*
X598275Y98125D01*
X598192Y98417D01*
X597983Y98667D01*
X597608Y98833D01*
X597108Y98917D01*
X596817Y99083D01*
X596692Y99375D01*
X596775Y99667D01*
X596983Y99875D01*
X597275Y100000D01*
X597567D01*
X597858Y99917D01*
X598108Y99708D01*
G01X599250Y100000D02*
X599833Y97500D01*
X600500Y100000D01*
X601167Y97500D01*
X601750Y100000D01*
G01X603600Y97500D02*
Y100000D01*
X603100Y99500D01*
G01Y97500D02*
X604100D01*
G01X592155Y95503D02*
X605955D01*
Y54103D01*
X592155D01*
Y95503D01*
G01X619500Y81017D02*
X617000D01*
Y82058D01*
X617125Y82392D01*
X617292Y82600D01*
X617625Y82683D01*
X617958Y82600D01*
X618167Y82350D01*
X618292Y82058D01*
Y81017D01*
G01Y82058D02*
X619500Y82683D01*
G01Y85450D02*
X617000D01*
X618792Y83908D01*
Y85992D01*
G01X619500Y88050D02*
X619458Y88342D01*
X619333Y88675D01*
X619125Y88883D01*
X618833Y88967D01*
X618542Y88883D01*
X618292Y88633D01*
X618167Y88258D01*
Y87842D01*
X618083Y87592D01*
X617875Y87383D01*
X617583Y87300D01*
X617292Y87425D01*
X617083Y87717D01*
X617000Y88050D01*
X617083Y88383D01*
X617292Y88675D01*
X617583Y88800D01*
X617875Y88717D01*
X618083Y88508D01*
X618167Y88258D01*
Y87842D01*
X618292Y87467D01*
X618542Y87217D01*
X618833Y87133D01*
X619125Y87217D01*
X619333Y87425D01*
X619458Y87758D01*
X619500Y88050D01*
G01X619000Y90233D02*
X619292Y90483D01*
X619458Y90817D01*
X619500Y91192D01*
X619458Y91525D01*
X619250Y91858D01*
X619000Y92067D01*
X618750Y92108D01*
X618458Y92025D01*
X618250Y91733D01*
X618167Y91442D01*
Y91067D01*
G01Y91442D02*
X618042Y91692D01*
X617833Y91900D01*
X617583Y91983D01*
X617333Y91900D01*
X617125Y91692D01*
X617000Y91317D01*
X617042Y90942D01*
X617208Y90567D01*
G01X585000Y82200D02*
X581000D01*
Y74800D01*
G01X626000Y70017D02*
X628500D01*
Y71683D01*
G01Y74783D02*
Y73117D01*
X626000D01*
Y74783D01*
G01X627208Y74117D02*
Y73117D01*
G01X628500Y76133D02*
X626000D01*
Y76967D01*
X626125Y77300D01*
X626292Y77550D01*
X626542Y77758D01*
X626833Y77925D01*
X627250Y77967D01*
X627667Y77925D01*
X627958Y77758D01*
X628208Y77550D01*
X628375Y77300D01*
X628500Y76967D01*
Y76133D01*
G01Y80150D02*
X626000D01*
X626500Y79650D01*
G01X628500D02*
Y80650D01*
G01X637088Y80203D02*
Y69403D01*
X631888D01*
Y80203D01*
X637088D01*
G01X633726Y218159D02*
X634059Y218692D01*
X634259Y219292D01*
Y219826D01*
X634059Y220359D01*
X633726Y220759D01*
X633259Y220959D01*
X632792Y220826D01*
X632392Y220492D01*
X632126Y219892D01*
X631992Y219092D01*
X631726Y218626D01*
X631259Y218426D01*
X630792Y218559D01*
X630459Y218892D01*
X630259Y219359D01*
Y219826D01*
X630392Y220292D01*
X630726Y220692D01*
G01X634259Y224159D02*
X630259D01*
G01X631592Y228759D02*
X634259D01*
G01X630526D02*
X630459Y228626D01*
X630326D01*
X630259Y228759D01*
X630326Y228892D01*
X630459D01*
X630526Y228759D01*
G01X630259Y233359D02*
X634259D01*
G01X631592Y232426D02*
Y234292D01*
G01X585967Y348500D02*
Y346000D01*
X587633D01*
G01X590733D02*
X589067D01*
Y348500D01*
X590733D01*
G01X590067Y347292D02*
X589067D01*
G01X592083Y346000D02*
Y348500D01*
X592917D01*
X593250Y348375D01*
X593500Y348208D01*
X593708Y347958D01*
X593875Y347667D01*
X593917Y347250D01*
X593875Y346833D01*
X593708Y346542D01*
X593500Y346292D01*
X593250Y346125D01*
X592917Y346000D01*
X592083D01*
G01X596100D02*
Y348500D01*
X595600Y348000D01*
G01Y346000D02*
X596600D01*
G01X598408Y347042D02*
X598700Y347333D01*
X598950Y347500D01*
X599283Y347583D01*
X599575Y347500D01*
X599783Y347333D01*
X599950Y347083D01*
X599992Y346792D01*
X599950Y346542D01*
X599783Y346292D01*
X599533Y346083D01*
X599242Y346000D01*
X598908Y346083D01*
X598617Y346333D01*
X598450Y346708D01*
X598408Y347125D01*
X598492Y347667D01*
X598617Y347958D01*
X598825Y348250D01*
X599117Y348458D01*
X599408Y348500D01*
X599700Y348417D01*
X599908Y348208D01*
G01X599000Y384900D02*
X598958Y384567D01*
X598792Y384275D01*
X598542Y384025D01*
X598250Y383858D01*
X597917Y383775D01*
X597583D01*
X597250Y383858D01*
X596958Y384025D01*
X596708Y384275D01*
X596542Y384567D01*
X596500Y384900D01*
X596542Y385233D01*
X596708Y385525D01*
X596958Y385775D01*
X597250Y385942D01*
X597583Y386025D01*
X597917D01*
X598250Y385942D01*
X598542Y385775D01*
X598792Y385525D01*
X598958Y385233D01*
X599000Y384900D01*
G01X598333Y385233D02*
X599000Y385733D01*
G01X598500Y387083D02*
X598792Y387333D01*
X598958Y387667D01*
X599000Y388042D01*
X598958Y388375D01*
X598750Y388708D01*
X598500Y388917D01*
X598250Y388958D01*
X597958Y388875D01*
X597750Y388583D01*
X597667Y388292D01*
Y387917D01*
G01Y388292D02*
X597542Y388542D01*
X597333Y388750D01*
X597083Y388833D01*
X596833Y388750D01*
X596625Y388542D01*
X596500Y388167D01*
X596542Y387792D01*
X596708Y387417D01*
G01X599000Y391100D02*
X596500D01*
X597000Y390600D01*
G01X599000D02*
Y391600D01*
G01X623285Y336676D02*
Y353376D01*
X602385D01*
Y336676D01*
X623285D01*
G01Y380376D02*
Y397076D01*
X602385D01*
Y380376D01*
X623285D01*
G01X605000Y404017D02*
X602500D01*
Y405017D01*
X602625Y405350D01*
X602917Y405600D01*
X603250Y405683D01*
X603583Y405600D01*
X603833Y405392D01*
X603958Y405017D01*
Y404017D01*
G01X605000Y407117D02*
X602500D01*
Y408158D01*
X602625Y408492D01*
X602792Y408700D01*
X603125Y408783D01*
X603458Y408700D01*
X603667Y408450D01*
X603792Y408158D01*
Y407117D01*
G01Y408158D02*
X605000Y408783D01*
G01X603958Y410258D02*
X603667Y410550D01*
X603500Y410800D01*
X603417Y411133D01*
X603500Y411425D01*
X603667Y411633D01*
X603917Y411800D01*
X604208Y411842D01*
X604458Y411800D01*
X604708Y411633D01*
X604917Y411383D01*
X605000Y411092D01*
X604917Y410758D01*
X604667Y410467D01*
X604292Y410300D01*
X603875Y410258D01*
X603333Y410342D01*
X603042Y410467D01*
X602750Y410675D01*
X602542Y410967D01*
X602500Y411258D01*
X602583Y411550D01*
X602792Y411758D01*
G01X604625Y413233D02*
X604833Y413483D01*
X604958Y413775D01*
X605000Y414150D01*
X604917Y414525D01*
X604750Y414817D01*
X604458Y415025D01*
X604125Y415067D01*
X603792Y414983D01*
X603583Y414775D01*
X603417Y414483D01*
X603375Y414192D01*
X603417Y413900D01*
X603583Y413525D01*
X602500Y413650D01*
Y414775D01*
G01X609500Y404017D02*
X607000D01*
Y405017D01*
X607125Y405350D01*
X607417Y405600D01*
X607750Y405683D01*
X608083Y405600D01*
X608333Y405392D01*
X608458Y405017D01*
Y404017D01*
G01X609500Y407117D02*
X607000D01*
Y408158D01*
X607125Y408492D01*
X607292Y408700D01*
X607625Y408783D01*
X607958Y408700D01*
X608167Y408450D01*
X608292Y408158D01*
Y407117D01*
G01Y408158D02*
X609500Y408783D01*
G01X608458Y410258D02*
X608167Y410550D01*
X608000Y410800D01*
X607917Y411133D01*
X608000Y411425D01*
X608167Y411633D01*
X608417Y411800D01*
X608708Y411842D01*
X608958Y411800D01*
X609208Y411633D01*
X609417Y411383D01*
X609500Y411092D01*
X609417Y410758D01*
X609167Y410467D01*
X608792Y410300D01*
X608375Y410258D01*
X607833Y410342D01*
X607542Y410467D01*
X607250Y410675D01*
X607042Y410967D01*
X607000Y411258D01*
X607083Y411550D01*
X607292Y411758D01*
G01X609500Y414650D02*
X607000D01*
X608792Y413108D01*
Y415192D01*
G01X625333Y398467D02*
X625133Y398067D01*
X625000Y397600D01*
Y397067D01*
X625200Y396467D01*
X625533Y396000D01*
X625933Y395667D01*
X626600Y395400D01*
X627200Y395333D01*
X627800Y395467D01*
X628200Y395667D01*
X628600Y396067D01*
X628867Y396533D01*
X629000Y397000D01*
Y397467D01*
X628867Y397933D01*
X628667Y398333D01*
X628400Y398667D01*
G01X600000Y398333D02*
Y395667D01*
X596000D01*
Y398333D01*
G01X597933Y397267D02*
Y395667D01*
G54D17*
G01X40109Y365933D02*
X36109D01*
G01X36128Y377132D02*
X40128D01*
G01X43807Y390868D02*
X47807D01*
G01X544500Y260971D02*
X540500D01*
G01Y271971D02*
X544500D01*
G01X618800Y74500D02*
X619900D01*
G01X616100D02*
X617200D01*
G01X613598Y405836D02*
X614698D01*
G01X610898D02*
X611998D01*
G01X618598Y405936D02*
X619698D01*
G01X615898D02*
X616998D01*
M02*
